G04 ================== begin FILE IDENTIFICATION RECORD ==================*
G04 Layout Name:  t6mg_pdb_a_v02_0109_1330.brd*
G04 Film Name:    in2*
G04 File Format:  Gerber RS274X*
G04 File Origin:  Cadence Allegro 16.3-S038*
G04 Origin Date:  Mon Jan 13 14:11:53 2014*
G04 *
G04 Layer:  DRAWING FORMAT/TITLE_BLOCK*
G04 Layer:  VIA CLASS/IN2*
G04 Layer:  PIN/IN2*
G04 Layer:  MANUFACTURING/PHOTOPLOT_OUTLINE*
G04 Layer:  ETCH/IN2*
G04 Layer:  DRAWING FORMAT/TITLE_DATA_IN2*
G04 *
G04 Offset:    (0.00 0.00)*
G04 Mirror:    No*
G04 Mode:      Positive*
G04 Rotation:  0*
G04 FullContactRelief:  No*
G04 UndefLineWidth:     6.00*
G04 ================== end FILE IDENTIFICATION RECORD ====================*
%FSLAX25Y25*MOIN*%
%IR0*IPPOS*OFA0.00000B0.00000*MIA0B0*SFA1.00000B1.00000*%
%ADD10C,.02*%
%ADD12C,.04*%
%ADD11C,.063*%
%ADD17C,.046*%
%ADD16C,.064*%
%ADD15C,.055*%
%ADD14C,.093*%
%ADD13C,.077*%
%ADD18C,.025*%
%ADD19C,.018*%
%ADD20C,.005*%
%ADD21C,.006*%
%ADD32C,.03004*%
%ADD28C,.05004*%
%ADD27C,.06204*%
%ADD26C,.07304*%
%ADD33C,.05604*%
%ADD31C,.07404*%
%ADD30C,.06504*%
%ADD38C,.08704*%
%ADD24C,.08407*%
%ADD37C,.08409*%
%ADD29C,.10504*%
%ADD34C,.40406*%
%ADD35C,.24506*%
%ADD22C,.16406*%
%ADD25C,.13266*%
%ADD36C,.35606*%
%ADD23C,.15806*%
G75*
%LPD*%
G75*
G36*
G01X104331Y2004D02*
G02X100429Y5906I0J3902D01*
G01Y9843D01*
G03X92520Y17752I-7909J0D01*
G01X5906D01*
G02X2004Y21654I0J3902D01*
G01Y2064961D01*
G02X5905Y2068862I3901J0D01*
G01X92520D01*
G03X100429Y2076772I0J7909D01*
G01Y2080709D01*
G02X104331Y2084610I3902J-1D01*
G01X397638D01*
G02X403508Y2078740I0J-5870D01*
G01Y7874D01*
G02X397638Y2004I-5870J0D01*
G01X104331D01*
G37*
%LPC*%
G75*
G36*
G01X104331Y3997D02*
X104330D01*
G02X102422Y5906I0J1908D01*
G01Y9843D01*
G03X92520Y19745I-9903J-1D01*
G01X91602D01*
Y19746D01*
X5906D01*
Y19745D01*
X5905D01*
G02X3998Y21711I1J1908D01*
G01Y795858D01*
X3587Y796269D01*
Y803272D01*
X3998Y803683D01*
Y2064961D01*
G02X4556Y2066310I1908J1D01*
G02X5964Y2066868I1349J-1349D01*
G01X92520D01*
G03X99522Y2069769I-1J9903D01*
G03X102422Y2076772I-7003J7002D01*
G01Y2080709D01*
G02X104330Y2082617I1908J0D01*
G01X104331D01*
Y2082616D01*
X397638D01*
G02X401514Y2078740I0J-3876D01*
G01Y1915551D01*
X401515Y1915541D01*
Y1915529D01*
X401514D01*
Y7874D01*
G02X397638Y3998I-3876J0D01*
G01X104331D01*
Y3997D01*
G37*
%LPD*%
G75*
G36*
G01X390983Y169633D02*
X390984Y156462D01*
Y85012D01*
X378522Y72550D01*
G02X376851Y73523I-707J707D01*
G03X365099Y61771I-17009J5257D01*
G02X366072Y60100I266J-964D01*
G01X359641Y53669D01*
X359517Y53633D01*
G03X358487Y52603I414J-1444D01*
G01X358451Y52479D01*
X356885Y50913D01*
X356230Y50258D01*
X351025Y45052D01*
X345743D01*
X340498Y39808D01*
X339838Y39148D01*
X338263Y37573D01*
G02X337849Y37429I-355J353D01*
G01X337795Y37436D01*
X337770Y37442D01*
G03X339922Y34198I-604J-2737D01*
G02X340914Y34107I492J-90D01*
G01Y32504D01*
G02X340679Y32080I-500J0D01*
G03X343651I1486J-2375D01*
G02X343416Y32504I265J424D01*
G01Y33960D01*
G02X344237Y34344I500J0D01*
G01X344402Y34206D01*
X344441Y34045D01*
G03X345119Y32790I2723J661D01*
G03X347289Y31906I2045J1915D01*
G03X349540Y33219I-124J2799D01*
G02X349964Y33454I424J-265D01*
G01X351301D01*
X352280Y34432D01*
X352403Y34555D01*
X352698Y34850D01*
G02X354391Y34309I707J-707D01*
G03X354459Y33979I2773J399D01*
G03X355699Y32317I2706J726D01*
G03X355798Y32259I1466J2388D01*
G02X356018Y30679I-487J-873D01*
G01X355672Y30333D01*
G02X354967Y30331I-354J354D01*
G01X354878Y30419D01*
X354841Y30538D01*
G03X351332Y27029I-2676J-833D01*
G01X351450Y26992D01*
X351537Y26905D01*
G02Y26198I-354J-354D01*
G01X351487Y26148D01*
X351466Y26127D01*
X351296Y25956D01*
X349964D01*
G02X349540Y26191I0J500D01*
G03Y23219I-2375J-1486D01*
G02X349964Y23454I424J-265D01*
G01X351422D01*
G02X351806Y22633I0J-500D01*
G01X351668Y22468D01*
X351507Y22429D01*
G03X353180Y22317I658J-2724D01*
G02X352835Y23956I362J932D01*
G01X352914Y24035D01*
G02X354553Y23690I707J-707D01*
G03X358180Y27317I2612J1015D01*
G02X357835Y28956I362J932D01*
G01X357914Y29035D01*
G02X359553Y28690I707J-707D01*
G03X363180Y32317I2612J1015D01*
G02X362835Y33956I362J932D01*
G01X379560Y50681D01*
X379682Y50717D01*
G03X380698Y51733I-425J1441D01*
G01X380734Y51855D01*
X397801Y68922D01*
G02X399508Y68215I707J-707D01*
G01Y7874D01*
G02X397638Y6004I-1870J0D01*
G01X104929D01*
G02X104429Y6504I0J500D01*
G01Y9843D01*
G03X92520Y21752I-11909J0D01*
G01X34944D01*
G02X34405Y23594I0J1000D01*
G03X25553I-4426J6906D01*
G02X25014Y21752I-539J-842D01*
G01X6504D01*
G02X6004Y22252I0J500D01*
G01Y699989D01*
G02X7195Y700971I1000J0D01*
G03Y705883I478J2456D01*
G02X6004Y706865I-191J982D01*
G01Y707863D01*
G02X7195Y708845I1000J0D01*
G03Y713757I478J2456D01*
G02X6004Y714739I-191J982D01*
G01Y715737D01*
G02X7195Y716719I1000J0D01*
G03Y721631I478J2456D01*
G02X6004Y722613I-191J982D01*
G01Y723611D01*
G02X7195Y724593I1000J0D01*
G03Y729505I478J2456D01*
G02X6004Y730487I-191J982D01*
G01Y739359D01*
G02X7195Y740341I1000J0D01*
G03Y745253I478J2456D01*
G02X6004Y746235I-191J982D01*
G01Y747233D01*
G02X7195Y748215I1000J0D01*
G03X7250Y748205I475J2456D01*
G03X10160Y750400I423J2466D01*
G02X11857Y750961I990J-146D01*
G01X14242Y748576D01*
X17418D01*
X23791Y742203D01*
G02X23762Y740761I-707J-707D01*
G03X22897Y738640I1627J-1900D01*
G03X26480Y736609I2492J220D01*
G03X27871Y738542I-1090J2252D01*
G02X29570Y739121I992J-128D01*
G01X30815Y737876D01*
X36076D01*
X37150Y736802D01*
Y664929D01*
X42336Y659742D01*
X74412Y627666D01*
Y525339D01*
X69653Y520580D01*
G02X68046Y520852I-707J707D01*
G03X67892Y521133I-2794J-1349D01*
G03X62233Y518794I-2638J-1632D01*
G03X62720Y517710I3021J706D01*
G02X61903Y516134I-817J-576D01*
G01X61722D01*
X26068Y480479D01*
Y457092D01*
X12348Y443372D01*
Y367834D01*
X22780Y357402D01*
X22888D01*
X24160Y356130D01*
X25849D01*
G02X26685Y354581I0J-1000D01*
G03X32722Y348911I3511J-2310D01*
G02X34322Y348112I600J-799D01*
G01Y309186D01*
G02X32722Y308387I-1000J0D01*
G03Y301667I-2525J-3360D01*
G02X34322Y300868I600J-799D01*
G01Y293074D01*
G02X32965Y292140I-1000J0D01*
G03X23156Y289053I-2986J-7640D01*
G03X26068Y277290I6823J-4553D01*
G03X37248Y280699I3911J7210D01*
G02X39134Y280236I886J-463D01*
G01Y263575D01*
X51827Y250882D01*
X51902Y250654D01*
X51872Y250462D01*
X51854Y250402D01*
X51844Y250364D01*
G03X56087Y252557I3135J-864D01*
G01X55938Y252611D01*
X55757Y252869D01*
Y253028D01*
G02X56257Y253528I500J0D01*
G01X57465D01*
X63559Y259621D01*
X64325Y260387D01*
X65188Y261250D01*
X65360Y261270D01*
G03X65987Y261408I-382J3230D01*
G02X67296Y260457I309J-951D01*
G01Y258587D01*
X66342Y257633D01*
X66067Y257565D01*
G03X61838Y253657I-1088J-3065D01*
G03X66845Y251836I3141J843D01*
G03X67266Y252188I-1868J2662D01*
G03X67273Y252195I-2296J2303D01*
G03X67278Y252200I-2297J2302D01*
G02X68978Y251486I700J-714D01*
G01Y250269D01*
X66342Y247633D01*
X66067Y247565D01*
G03X62847Y242044I-1089J-3065D01*
G03X68226Y244323I2132J2456D01*
G03X68086Y245460I-3247J177D01*
G01X68045Y245593D01*
X68112Y245863D01*
X69070Y246821D01*
G02X70752Y246144I683J-732D01*
G01Y241338D01*
X44488Y215074D01*
Y192557D01*
X47474Y189571D01*
Y175528D01*
X52754Y170248D01*
X61661D01*
X62098Y169986D01*
X62163Y169874D01*
G03X66828Y168825I2816J1626D01*
G03X67800Y169882I-1849J2675D01*
G03X62163Y173128I-2821J1618D01*
G01X62099Y173016D01*
X61661Y172752D01*
X58223D01*
G02X57439Y174373I0J1000D01*
G03X57426Y178642I-2460J2127D01*
G03X53891Y179565I-2447J-2142D01*
G01X53616Y179633D01*
X51412Y181837D01*
Y189874D01*
G02X51874Y190374I500J1D01*
G01X54160D01*
G02X54483Y190227I-32J-499D01*
G01X61827Y182882D01*
X61902Y182654D01*
X61872Y182462D01*
X61854Y182402D01*
X61844Y182364D01*
G03X64702Y184740I3135J-864D01*
G01X64545Y184898D01*
X56952Y192491D01*
G02X57029Y193975I707J707D01*
G03X58218Y196795I-2050J2525D01*
G03X57985Y197741I-3239J-296D01*
G03X57439Y198627I-3006J-1241D01*
G02X58223Y200248I784J621D01*
G01X61661D01*
X62098Y199986D01*
X62163Y199874D01*
G03Y203126I2816J1626D01*
G01X62098Y203014D01*
X61661Y202752D01*
X58223D01*
G02X57439Y204373I0J1000D01*
G03X56313Y209466I-2460J2127D01*
G01X56184Y209524D01*
X55872Y209984D01*
Y213018D01*
X74624Y231770D01*
X74921D01*
X76046Y232895D01*
X76516Y233365D01*
X80254Y237104D01*
Y344480D01*
X49636Y375098D01*
Y449086D01*
G02X51315Y449766I999J-54D01*
G03X65355Y444272I14040J15194D01*
G03X71134Y445096I-1J20687D01*
G03X86042Y464960I-5779J19864D01*
G03X61331Y485252I-20687J0D01*
G03X58298Y484407I4019J-20293D01*
G02X57250Y486054I-341J940D01*
G01X69226Y498030D01*
X75358D01*
X94448Y517120D01*
G02X96130Y516443I683J-732D01*
G01Y459319D01*
X73056Y436245D01*
Y365672D01*
X97021Y341706D01*
X200391D01*
X205352Y336745D01*
G02X204634Y335038I-707J-707D01*
G03X207849Y331823I-37J-3252D01*
G02X209556Y332541I1000J11D01*
G01X317370Y224728D01*
X319532D01*
X319645Y224665D01*
G03X319709Y224631I736J1309D01*
G03X319764Y224605I669J1345D01*
G03X319957Y224535I608J1374D01*
G01X320082Y224499D01*
X328490Y216091D01*
Y197703D01*
X337981Y188212D01*
X364322D01*
X368260Y192150D01*
Y198280D01*
X367695Y198845D01*
X367459Y199081D01*
X365583Y200956D01*
X364737D01*
G02X364101Y202679I55J999D01*
G03X361158Y207320I-1936J2026D01*
G01X361071Y207286D01*
X360638D01*
G02X359765Y208660I55J999D01*
G03X356560Y212442I-2600J1046D01*
G01X356535Y212436D01*
X356481Y212429D01*
G02X356067Y212573I-59J497D01*
G01X343865Y224774D01*
X340062D01*
X334779Y230057D01*
X334115Y230722D01*
X332526Y232311D01*
X332490Y232435D01*
G03X331460Y233465I-1444J-414D01*
G01X331336Y233501D01*
X315574Y249263D01*
G02X315725Y250802I707J708D01*
G03X316124Y251158I-785J1281D01*
G03X315500Y253477I-1183J925D01*
G03X315134Y253572I-557J-1394D01*
G03X313480Y252434I-194J-1489D01*
G01X313447Y252297D01*
X313347Y252197D01*
G02X312640I-353J354D01*
G01X312066Y252771D01*
Y257654D01*
X308344Y261375D01*
G02X309052Y263082I707J707D01*
G01X310214D01*
X320390Y252906D01*
G02X320180Y251388I-742J-671D01*
G03X322244Y249324I781J-1283D01*
G02X323762Y249534I847J-532D01*
G01X352390Y220906D01*
X371648D01*
X390983Y201571D01*
Y169633D01*
G37*
G36*
G01X324136Y910220D02*
G03Y904820I-751J-2700D01*
G02X325382Y903914I247J-970D01*
G01Y901996D01*
X339523Y887854D01*
X361990D01*
X366888Y892752D01*
Y897243D01*
X366399Y897732D01*
X364672Y899458D01*
X360458D01*
G02X359959Y899919I0J500D01*
G01Y899920D01*
G03X357794Y896974I-2794J-215D01*
G01X357952Y897011D01*
X358153Y896956D01*
X358637D01*
G02X359519Y895627I-63J-999D01*
G03X359434Y894076I2646J-923D01*
G02X359300Y893610I-487J-112D01*
G01X357628Y891938D01*
X355531D01*
G02X354646Y893402I0J1000D01*
G03X349684I-2481J1303D01*
G02X348799Y891938I-885J-464D01*
G01X345531D01*
G02X344646Y893402I0J1000D01*
G03X344913Y895254I-2481J1303D01*
G03X344821Y895598I-2747J-550D01*
G03X343651Y897080I-2656J-894D01*
G02X343416Y897504I265J424D01*
G01Y899105D01*
G02X343916Y899605I500J0D01*
G01X344098D01*
X344375Y899374D01*
X344408Y899196D01*
G03X349967Y899690I2756J506D01*
G03X349688Y900924I-2802J15D01*
G03X349377Y901425I-2523J-1219D01*
G03X348659Y902076I-2213J-1719D01*
G03X344527Y900649I-1494J-2371D01*
G02X342892Y900317I-927J375D01*
G01X342777Y900432D01*
G02X343109Y902067I707J708D01*
G03X339527Y905649I-944J2638D01*
G02X337892Y905317I-927J375D01*
G01X337777Y905432D01*
G02X338109Y907067I707J708D01*
G03X339861Y908941I-944J2638D01*
G03X336280Y912364I-2696J764D01*
G02X335012Y913265I-269J964D01*
G01Y921753D01*
X336992Y923733D01*
Y932309D01*
G02X338122Y933239I999J-63D01*
G01X355708Y915653D01*
Y912364D01*
G02X355504Y911961I-500J0D01*
G03X354482Y910514I1660J-2257D01*
G03X354404Y910183I2683J-807D01*
G03X354382Y909378I2761J-478D01*
G03X355451Y907488I2783J327D01*
G03X359922Y909197I1715J2216D01*
G01X359955Y909375D01*
X360232Y909606D01*
X360414D01*
G02X360914Y909106I0J-500D01*
G01Y907504D01*
G02X360679Y907080I-500J0D01*
G03X363651I1486J-2375D01*
G02X363416Y907504I265J424D01*
G01Y915734D01*
X345135Y934016D01*
X345100Y934140D01*
G03X344471Y934987I-1444J-415D01*
G01X344426Y935016D01*
X337378Y942064D01*
Y951465D01*
X337172Y951671D01*
Y952759D01*
X316638Y973294D01*
G02X316738Y974796I707J707D01*
G01X366517D01*
X390234Y951079D01*
Y782501D01*
X361807Y754074D01*
X361762Y754045D01*
G03X361133Y753198I815J-1262D01*
G01X361098Y753074D01*
X359288Y751264D01*
X348657D01*
X335914Y738522D01*
Y737504D01*
G02X335679Y737080I-500J0D01*
G03X335031Y736520I1487J-2375D01*
G03X334720Y736072I2135J-1814D01*
G03X336802Y731927I2446J-1367D01*
G01X336981Y731903D01*
X337440Y731411D01*
Y727999D01*
X337151Y727689D01*
X336981Y727507D01*
X336803Y727483D01*
G03X335409Y726888I362J-2778D01*
G03X334964Y726438I1757J-2183D01*
G03X334945Y722996I2202J-1733D01*
G03X339643Y723394I2221J1708D01*
G02X341233Y723634I884J-468D01*
G01X341276Y723591D01*
X341346Y723522D01*
X344510D01*
X344753Y723279D01*
X344784Y723230D01*
G03X349963Y724864I2382J1475D01*
G03X344828Y726248I-2797J-160D01*
G02X344410Y726024I-417J276D01*
G01X343491D01*
G02X342995Y726457I0J500D01*
G01X342967Y726665D01*
X343270Y727125D01*
X343393Y727185D01*
G03X343687Y732059I-1226J2520D01*
G02X343458Y732479I271J420D01*
G01Y734113D01*
G02X343914Y734611I500J0D01*
G01X344068Y734625D01*
X344375Y734391D01*
X344410Y734200D01*
G03X349903Y735310I2757J504D01*
G01X349897Y735335D01*
X349890Y735392D01*
G02X350034Y735803I497J57D01*
G01X355613Y741382D01*
X365058D01*
X376945Y753269D01*
X377069Y753304D01*
G03X378098Y754333I-415J1444D01*
G01X378133Y754457D01*
X397801Y774125D01*
G02X399508Y773418I707J-707D01*
G01Y211236D01*
G02X397801Y210529I-1000J0D01*
G01X379784Y228546D01*
X353807D01*
X312167Y270186D01*
X310830D01*
X309089Y271927D01*
X305317D01*
X216532Y360712D01*
X106019D01*
X92724Y374007D01*
Y415756D01*
G02X93224Y416234I500J-23D01*
G01X93231D01*
G03X94682Y417378I-8J1502D01*
G02X96346Y417793I957J-292D01*
G01X104915Y409224D01*
X105121D01*
X105413Y408932D01*
Y408723D01*
G02X105049Y408242I-500J0D01*
G01X105048D01*
G03X105022Y408234I429J-1439D01*
G03X104840Y408167I427J-1440D01*
G03X104329Y405796I611J-1372D01*
G03X106791Y406116I1122J999D01*
G03X106946Y406942I-1340J679D01*
G03X106684Y407653I-1495J-147D01*
G02X107504Y409224I821J571D01*
G01X115724D01*
G02X116638Y407815I1J-1000D01*
G03X120802Y402506I3282J-1713D01*
G03X123617Y406303I-882J3596D01*
G02X125322Y407065I998J55D01*
G01X127537Y404850D01*
X136100D01*
G02X136555Y404559I1J-500D01*
G01Y404558D01*
G03Y407646I3365J1544D01*
G01Y407645D01*
G02X136100Y407354I-454J209D01*
G01X128573D01*
X124199Y411728D01*
X123194D01*
G02X122498Y413445I1J1000D01*
G03X117342I-2578J2657D01*
G02X116646Y411728I-697J-717D01*
G01X105951D01*
X95826Y421853D01*
X95791Y421977D01*
G03X93973Y423017I-1444J-415D01*
G02X92724Y423923I-250J969D01*
G01Y426120D01*
X113718Y447114D01*
Y684022D01*
X112099Y685642D01*
X111408Y686333D01*
G02X112140Y688015I731J682D01*
G01X233482D01*
X320653Y600844D01*
G02X320761Y600298I-353J-354D01*
G01X320684Y600112D01*
X320627Y600048D01*
G03X322749Y597926I1115J-1007D01*
G01X322813Y597983D01*
X322999Y598060D01*
G02X323545Y597952I192J-461D01*
G01X328384Y593113D01*
Y585555D01*
X328322Y585442D01*
G03Y583988I1314J-727D01*
G01X328384Y583875D01*
Y547819D01*
X330529Y545674D01*
X338100Y538104D01*
X362154D01*
X365016Y540965D01*
X366750Y542699D01*
Y547283D01*
X365921Y548112D01*
X364554Y549478D01*
X360456D01*
G02X359958Y549937I0J500D01*
G03X358677Y552065I-2792J-231D01*
G03X356904Y552495I-1511J-2360D01*
G03X355596Y552026I262J-2790D01*
G03X354937Y551403I1570J-2321D01*
G03X357752Y546964I2229J-1699D01*
G01X357804Y546976D01*
X358645D01*
G02X359531Y545659I-63J-999D01*
G03X359370Y544896I2635J-954D01*
G03X359435Y544076I2796J-191D01*
G02X359301Y543610I-487J-112D01*
G01X357645Y541954D01*
X355541D01*
G02X354653Y543414I0J1000D01*
G03X349679I-2487J1291D01*
G02X348791Y541954I-888J-460D01*
G01X345541D01*
G02X344653Y543414I0J1000D01*
G03X344513Y546236I-2487J1291D01*
G03X344303Y546517I-2345J-1533D01*
G03X343788Y546990I-2138J-1811D01*
G01X343694Y547057D01*
X343468Y547472D01*
Y548881D01*
G02X343968Y549381I500J0D01*
G01X344139D01*
X344409Y549172D01*
X344452Y549005D01*
G03X348941Y551873I2714J700D01*
G03X346767Y552478I-1775J-2168D01*
G03X344667Y550973I399J-2774D01*
G02X343068Y550718I-892J452D01*
G01X342944Y550842D01*
G02X343398Y552188I894J448D01*
G03X344779Y555718I-1232J2517D01*
G03X344303Y556518I-2613J-1013D01*
G03X343700Y557050I-2136J-1813D01*
G03X343102Y557346I-1533J-2345D01*
G01X342995Y557384D01*
X342915Y557463D01*
G02Y558171I353J354D01*
G01X342928Y558184D01*
Y572791D01*
G02X344558Y573203I948J-320D01*
G01X354935Y562826D01*
G02X355001Y561484I-707J-707D01*
G03X354423Y560278I2165J-1779D01*
G03X358144Y557079I2743J-573D01*
G03X359522Y558188I-978J2626D01*
G03X359825Y558822I-2357J1516D01*
G01X359880Y558987D01*
X360173Y559179D01*
X360462Y559151D01*
G02X360914Y558653I-48J-498D01*
G01Y557504D01*
G02X360679Y557080I-500J0D01*
G03X363653I1487J-2375D01*
G02X363418Y557504I265J424D01*
G01Y561378D01*
X344379Y580417D01*
X344344Y580541D01*
G03X343315Y581570I-1444J-415D01*
G01X343191Y581605D01*
X340402Y584394D01*
Y600132D01*
X312011Y628523D01*
G02X312719Y630230I707J707D01*
G01X360970D01*
X389752Y601448D01*
Y429465D01*
X363534Y403247D01*
X363410Y403212D01*
G03X362381Y402183I415J-1444D01*
G01X362346Y402059D01*
X361449Y401162D01*
X347916D01*
X335914Y389159D01*
Y387504D01*
G02X335679Y387080I-500J0D01*
G03X336772Y381931I1486J-2375D01*
G02X337202Y381436I-70J-495D01*
G01Y377974D01*
G02X336772Y377479I-500J0D01*
G03X334423Y374129I393J-2774D01*
G03X334887Y373073I2742J575D01*
G03X339693Y373496I2278J1632D01*
G02X341302Y373772I902J-431D01*
G01X341640Y373434D01*
X341683D01*
X341975Y373142D01*
Y372934D01*
G02X341580Y372445I-500J0D01*
G01X341579D01*
G03X342751I586J-2740D01*
G01X342750D01*
G02X342355Y372934I105J489D01*
G01Y373142D01*
X342647Y373434D01*
X344378D01*
X344796Y373204D01*
X344863Y373108D01*
G03X345705Y372313I2303J1596D01*
G03X346761Y371932I1460J2392D01*
G03X349959Y374491I404J2773D01*
G03X344780Y376176I-2794J214D01*
G01Y376175D01*
G02X344354Y375938I-425J263D01*
G01X342676D01*
X342494Y376120D01*
X342396Y376217D01*
X342328Y376483D01*
X342368Y376616D01*
G02X342743Y376963I479J-142D01*
G01X342744D01*
G03X344295Y377884I-579J2741D01*
G03X344966Y379762I-2130J1820D01*
G03X343651Y382080I-2801J-57D01*
G02X343416Y382504I265J424D01*
G01Y384106D01*
G02X343916Y384606I500J0D01*
G01X344098D01*
X344375Y384375D01*
X344408Y384197D01*
G03X345881Y382214I2756J509D01*
G03X349929Y384245I1284J2491D01*
G03X349896Y385334I-2765J461D01*
G02X350030Y385800I487J112D01*
G01X354924Y390694D01*
X365724D01*
X374833Y399803D01*
X374957Y399838D01*
G03X375986Y400867I-415J1444D01*
G01X376021Y400991D01*
X398330Y423300D01*
Y602539D01*
X362061Y638808D01*
X303315D01*
X243034Y699089D01*
Y704046D01*
X244870Y705882D01*
X331912D01*
G02X332203Y705753I-47J-498D01*
G01X355080Y682876D01*
X355115Y682752D01*
G03X355245Y682439I1444J416D01*
G01X355308Y682326D01*
Y676007D01*
X355245Y675894D01*
G03X357873I1314J-727D01*
G01X357810Y676007D01*
Y682326D01*
X357873Y682439D01*
G03X356974Y684611I-1314J728D01*
G01X356850Y684646D01*
X333111Y708384D01*
X124224D01*
G02X123914Y708531I46J498D01*
G01X122439Y710006D01*
G02X122450Y711431I707J707D01*
G03X123303Y712630I-2530J2703D01*
G03X121856Y717290I-3383J1504D01*
G03X116604Y715780I-1936J-3156D01*
G03X116227Y714396I3316J-1647D01*
G03X116218Y714142I3693J-258D01*
G02X114511Y713437I-1000J2D01*
G01X110594Y717354D01*
Y755574D01*
X106028Y760140D01*
Y782319D01*
X110770Y787061D01*
Y792767D01*
G02X111830Y793765I1000J0D01*
G03Y796757I137J1496D01*
G02X110770Y797755I-60J998D01*
G01Y861835D01*
X108043Y864562D01*
G02X107896Y864894I352J355D01*
G01Y909302D01*
X92531Y924668D01*
G02X92461Y926005I707J707D01*
G03X90815Y928375I-1167J946D01*
G02X89496Y929260I-320J948D01*
G01Y934824D01*
X63249Y961072D01*
X36554D01*
G02X35599Y962374I-1J1000D01*
G03X35615Y962418I-2343J877D01*
G03X35638Y962483I-2346J867D01*
G01X35653Y962531D01*
G03X31245Y964750I-2390J739D01*
G02X29732Y964634I-806J591D01*
G01X27998Y966368D01*
G02X27858Y966802I353J354D01*
G03X25794Y964738I-2469J405D01*
G02X26228Y964598I80J-493D01*
G01X31899Y958927D01*
G02X31783Y957414I-707J-707D01*
G03X31245Y956876I1480J-2018D01*
G02X29732Y956760I-806J591D01*
G01X27998Y958494D01*
G02X27858Y958928I353J354D01*
G03X25794Y956864I-2469J405D01*
G02X26228Y956724I80J-493D01*
G01X27982Y954970D01*
Y946194D01*
X28496Y945680D01*
G02X28143Y944826I-353J-354D01*
G01X27834D01*
X27434Y945033D01*
X27366Y945120D01*
Y945121D01*
G03X23248Y944880I-1976J-1535D01*
G02X21685Y944690I-856J517D01*
G01X21452Y944923D01*
Y947324D01*
X18069Y950707D01*
X17996Y950942D01*
X18018Y951062D01*
Y951065D01*
G03X13160Y952210I-2471J395D01*
G03X13358Y950247I2387J-751D01*
G02X12546Y948762I-875J-486D01*
G01X10115D01*
X9718Y948970D01*
X9650Y949056D01*
X9649Y949058D01*
G03X7195Y949978I-1975J-1536D01*
G02X6004Y950960I-191J982D01*
G01Y951958D01*
G02X7195Y952940I1000J0D01*
G03Y957852I478J2456D01*
G02X6004Y958834I-191J982D01*
G01Y967706D01*
G02X7195Y968688I1000J0D01*
G03Y973600I478J2456D01*
G02X6004Y974582I-191J982D01*
G01Y975580D01*
G02X7195Y976562I1000J0D01*
G03Y981474I478J2456D01*
G02X6004Y982456I-191J982D01*
G01Y991328D01*
G02X7195Y992310I1000J0D01*
G03Y997222I478J2456D01*
G02X6004Y998204I-191J982D01*
G01Y999202D01*
G02X7195Y1000184I1000J0D01*
G03X9705Y1001180I478J2456D01*
G02X10112Y1001388I406J-292D01*
G01X15604D01*
X18050Y998942D01*
Y996403D01*
X20794Y993658D01*
X21572Y992880D01*
X22049D01*
G02X23002Y991580I-1J-1000D01*
G03X22963Y991442I2387J-749D01*
G03X22945Y991366I2426J-615D01*
G03X22938Y991332I2447J-522D01*
G03X22934Y991312I2451J-501D01*
G02X21800Y990557I-973J232D01*
G03X19510Y990625I-1331J-6224D01*
G03X19178Y990566I947J-6293D01*
G02X18000Y991322I-203J979D01*
G03X15301Y993319I-2453J-493D01*
G03X13958Y992762I246J-2490D01*
G03X14391Y988610I1589J-1933D01*
G02X14817Y987263I-462J-887D01*
G03X14725Y987077I5658J-2914D01*
G03X14103Y984333I5743J-2744D01*
G03X22939Y978468I6365J0D01*
G03X26310Y986858I-2471J5865D01*
G03X26112Y987274I-5842J-2526D01*
G02X26518Y988596I894J449D01*
G03X26882Y988821I-1129J2233D01*
G03X27201Y989104I-1495J2006D01*
G03X27616Y989689I-1812J1725D01*
G03X27625Y989706I-2206J1179D01*
G02X29226Y989964I894J-449D01*
G01X29519Y989671D01*
X30551Y988640D01*
X36135D01*
X44598Y997103D01*
Y1003791D01*
G02X44744Y1004144I500J0D01*
G01X57232Y1016631D01*
G02X58914Y1015962I683J-732D01*
G01Y1006089D01*
X72768Y992234D01*
X95652D01*
G02X96646Y991124I0J-1000D01*
G03X99632I1493J-165D01*
G02X100626Y992234I994J110D01*
G01X110030D01*
X115330Y986934D01*
X115576D01*
G02X116500Y985552I0J-1000D01*
G03X116572Y982554I3420J-1418D01*
G02X115668Y981128I-904J-426D01*
G01X106403D01*
X103098Y977822D01*
X100710Y975434D01*
Y972220D01*
G03X103613Y970604I1901J0D01*
G02X104193Y970567I264J-425D01*
G03X105099Y970162I1202J1473D01*
G03X105395Y970138I301J1877D01*
G01X112411D01*
X115195Y967354D01*
X115775D01*
G02X116668Y965903I1J-1000D01*
G03X123172I3252J-1769D01*
G02X124065Y967354I892J451D01*
G01X135775D01*
G02X136668Y965903I1J-1000D01*
G03X143172I3252J-1769D01*
G02X144065Y967354I892J451D01*
G01X172689D01*
X176480Y971145D01*
G03X173790Y973835I-1345J1345D01*
G01X171113Y971158D01*
X170116D01*
G02X169136Y972358I0J1000D01*
G03X164754Y974497I-2437J566D01*
G02X164199Y974340I-389J315D01*
G03X163043Y974275I-500J-1416D01*
G03X162320Y973520I655J-1351D01*
G03X162269Y972464I1379J-596D01*
G02X161317Y971158I-952J-306D01*
G01X144186D01*
G02X143274Y972566I1J1000D01*
G03X143361Y972768I-3355J1565D01*
G03X143622Y974101I-3441J1366D01*
G03X143442Y975274I-3702J32D01*
G03X143196Y975859I-3523J-1137D01*
G02X144081Y977324I885J465D01*
G01X172355D01*
X173264Y978233D01*
G02X173617Y978380I354J-353D01*
G01X175022D01*
G03Y982182I0J1901D01*
G01X171834D01*
X171392Y981740D01*
X170779Y981128D01*
X169946D01*
G02X169019Y982502I0J1000D01*
G03X169199Y983332I-2320J938D01*
G03X168443Y985233I-2500J107D01*
G02X169156Y986934I713J701D01*
G01X173008D01*
X174130Y988056D01*
X175742D01*
G03Y991860I0J1902D01*
G01X172554D01*
X171432Y990738D01*
X169418D01*
G02X168631Y992355I0J1000D01*
G03X164754Y995517I-1932J1589D01*
G02X164199Y995360I-389J315D01*
G03Y992528I-500J-1416D01*
G02X164757Y992368I167J-472D01*
G03X164767Y992355I1987J1518D01*
G02X163980Y990738I-787J-617D01*
G01X143965D01*
G02X143105Y992247I0J1000D01*
G03X143139Y995963I-3185J1887D01*
G02X144008Y997456I870J493D01*
G01X172963D01*
X174104Y996315D01*
G03X176794Y999005I1345J1345D01*
G01X174539Y1001260D01*
X169672D01*
G02X168736Y1002615I-1J1000D01*
G03X168924Y1003464I-2312J957D01*
G03X168894Y1003970I-2500J106D01*
G02X169881Y1005130I987J160D01*
G01X174788D01*
X177043Y1007385D01*
G03X174353Y1010075I-1345J1345D01*
G01X173212Y1008934D01*
X169649D01*
G02X168722Y1010308I0J1000D01*
G03X168909Y1011005I-2298J990D01*
G03X168850Y1011911I-2485J293D01*
G02X169757Y1013156I970J246D01*
G01X172622D01*
X172692Y1013226D01*
X172917Y1013450D01*
X173861Y1014394D01*
X175473D01*
G03Y1018198I0J1902D01*
G01X172285D01*
X171192Y1017105D01*
G02X170839Y1016958I-354J353D01*
G01X169378D01*
G02X168573Y1018456I63J999D01*
G03X164479Y1021310I-2149J1280D01*
G02X163924Y1021153I-389J315D01*
G03X163031Y1021187I-501J-1416D01*
G03X162101Y1020449I393J-1450D01*
G03X162487Y1018563I1323J-712D01*
G03X163773Y1018276I937J1174D01*
G02X164348Y1017616I105J-489D01*
G02X163470Y1016958I-941J341D01*
G01X156797D01*
X152661Y1021094D01*
X144094D01*
G02X143256Y1022528I63J999D01*
G03X143596Y1024576I-3336J1606D01*
G03X143521Y1024993I-3675J-446D01*
G03X143331Y1025574I-3602J-856D01*
G03X143271Y1025708I-3408J-1446D01*
G02X144192Y1027098I921J390D01*
G01X187114D01*
X189856Y1024356D01*
X251414D01*
X317160Y958615D01*
G02X317306Y958262I-354J-353D01*
G01Y942018D01*
X317243Y941905D01*
G03Y940451I1314J-727D01*
G01X317306Y940338D01*
Y928651D01*
X325382Y920575D01*
Y911126D01*
G02X324136Y910220I-999J64D01*
G37*
G36*
G01X362619Y1947867D02*
Y1951709D01*
X362816Y1951974D01*
X362975Y1952022D01*
G03X364277Y1952863I-810J2682D01*
G03X364783Y1953706I-2112J1841D01*
G03X364037Y1956790I-2618J999D01*
G03X363799Y1956981I-1870J-2086D01*
G01X363705Y1957049D01*
X363482Y1957462D01*
Y1960583D01*
X357363Y1966702D01*
X335512D01*
X330538Y1961727D01*
Y1946599D01*
X356869Y1920267D01*
X356907Y1920163D01*
G03X357904Y1919236I1411J517D01*
G01X358028Y1919200D01*
X363128Y1914100D01*
X369272D01*
X372985Y1910387D01*
G02X372773Y1908811I-707J-707D01*
G03X371256Y1906203I1485J-2609D01*
G01Y1906174D01*
G03X372140Y1904047I3001J0D01*
G02X372165Y1903365I-353J-354D01*
G03X371696Y1902633I2266J-1968D01*
G03X371617Y1902441I2734J-1237D01*
G01X371562Y1902294D01*
X371306Y1902116D01*
X367144D01*
X367031Y1902178D01*
G03X364890Y1900364I-725J-1315D01*
G03X367033Y1898550I1416J-500D01*
G01X367146Y1898612D01*
X369115D01*
X380372Y1887356D01*
G02X380518Y1887003I-354J-353D01*
G01Y1803491D01*
X373515Y1796488D01*
X334254D01*
X326410Y1788644D01*
Y1785684D01*
G02X324877Y1784892I-999J54D01*
G03Y1780148I-1492J-2372D01*
G02X326410Y1779356I534J-846D01*
G01Y1775054D01*
G02X324877Y1774262I-999J54D01*
G03Y1769518I-1492J-2372D01*
G02X326410Y1768726I534J-846D01*
G01Y1768356D01*
X316760Y1758706D01*
X162311D01*
X158661Y1755056D01*
X144036D01*
G02X143204Y1756518I55J999D01*
G03X136636I-3284J1710D01*
G02X135804Y1755056I-887J-463D01*
G01X125031D01*
G02X124715Y1755203I40J499D01*
G01X123513Y1756405D01*
G02X123374Y1756847I353J354D01*
G01X123391Y1756939D01*
X123405Y1756978D01*
G03X121131Y1754729I-3485J1250D01*
G01X121211Y1754757D01*
X121621D01*
X122270Y1754108D01*
G02X121916Y1753254I-354J-354D01*
G01X101934D01*
G02X101581Y1753400I0J500D01*
G01X83378Y1771605D01*
Y1775609D01*
G03X77374I-3002J0D01*
G01Y1768566D01*
G03X77524Y1767632I3001J3D01*
G03X78254Y1766444I2852J934D01*
G01X97446Y1747252D01*
X116036D01*
G02X116713Y1745570I-55J-999D01*
G01X100814Y1729670D01*
Y1499792D01*
X56762Y1455740D01*
Y1311160D01*
X57642Y1310280D01*
Y1306035D01*
X55042Y1303435D01*
Y1267807D01*
G02X54896Y1267454I-500J0D01*
G01X35425Y1247984D01*
X27832D01*
G02X27425Y1248192I-1J500D01*
G03Y1245272I-2032J-1460D01*
G02X27832Y1245480I406J-292D01*
G01X30197D01*
G02X31082Y1244015I0J-1000D01*
G03Y1241575I2185J-1220D01*
G02X30197Y1240110I-885J-465D01*
G01X27832D01*
X27431Y1240316D01*
X27363Y1240402D01*
X27346Y1240424D01*
G03X23511Y1240506I-1952J-1565D01*
G03X22948Y1238326I1882J-1649D01*
G03X22953Y1238303I2447J520D01*
G02X21976Y1237090I-977J-213D01*
G01X18968D01*
G02X17991Y1238303I0J1000D01*
G03X13111I-2440J555D01*
G02X12134Y1237090I-977J-213D01*
G01X8930D01*
X8822Y1237145D01*
G03X7164Y1237370I-1146J-2224D01*
G02X6004Y1238358I-160J987D01*
G01Y1239358D01*
G02X7164Y1240346I1000J1D01*
G03Y1245244I513J2449D01*
G02X6004Y1246232I-160J987D01*
G01Y1247232D01*
G02X7164Y1248220I1000J1D01*
G03Y1253118I513J2449D01*
G02X6004Y1254106I-160J987D01*
G01Y1255106D01*
G02X7164Y1256094I1000J1D01*
G03Y1260992I513J2449D01*
G02X6004Y1261980I-160J987D01*
G01Y1270854D01*
G02X7164Y1271842I1000J1D01*
G03Y1276740I513J2449D01*
G02X6004Y1277728I-160J987D01*
G01Y1286602D01*
G02X7164Y1287590I1000J1D01*
G03Y1292488I513J2449D01*
G02X6004Y1293476I-160J987D01*
G01Y1294476D01*
G02X7164Y1295464I1000J1D01*
G03Y1300362I513J2449D01*
G02X6004Y1301350I-160J987D01*
G01Y1302350D01*
G02X7164Y1303338I1000J1D01*
G03Y1308236I513J2449D01*
G02X6004Y1309224I-160J987D01*
G01Y1318098D01*
G02X7164Y1319086I1000J1D01*
G03Y1323984I513J2449D01*
G02X6004Y1324972I-160J987D01*
G01Y1325972D01*
G02X7164Y1326960I1000J1D01*
G03Y1331858I513J2449D01*
G02X6004Y1332846I-160J987D01*
G01Y1333846D01*
G02X7164Y1334834I1000J1D01*
G03Y1339732I513J2449D01*
G02X6004Y1340720I-160J987D01*
G01Y1349594D01*
G02X7164Y1350582I1000J1D01*
G03Y1355480I513J2449D01*
G02X6004Y1356468I-160J987D01*
G01Y1365342D01*
G02X7164Y1366330I1000J1D01*
G03Y1371228I513J2449D01*
G02X6004Y1372216I-160J987D01*
G01Y1381090D01*
G02X7164Y1382078I1000J1D01*
G03Y1386976I513J2449D01*
G02X6004Y1387964I-160J987D01*
G01Y2064362D01*
G02X6504Y2064862I500J0D01*
G01X92520D01*
G03X104429Y2076772I0J11909D01*
G01Y2080110D01*
G02X104929Y2080610I500J0D01*
G01X397638D01*
G02X399508Y2078740I0J-1870D01*
G01Y1538613D01*
G02X397801Y1537906I-1000J0D01*
G01X369309Y1566398D01*
X369273Y1566522D01*
G03X368602Y1567396I-1444J-414D01*
G01X363622Y1572376D01*
Y1592046D01*
G02X363826Y1592449I500J0D01*
G03X364626Y1596045I-1661J2256D01*
G03X363879Y1596922I-2461J-1340D01*
G03X359441Y1595365I-1714J-2217D01*
G01X359402Y1595204D01*
X359238Y1595067D01*
G02X358417Y1595450I-321J383D01*
G01X358416Y1596178D01*
Y1596906D01*
G02X358651Y1597330I500J0D01*
G03X355679I-1486J2375D01*
G02X355914Y1596906I-265J-424D01*
G01Y1595303D01*
G02X355414Y1594803I-500J0D01*
G01X355232D01*
X354955Y1595034D01*
X354922Y1595213D01*
G03X349367Y1594553I-2757J-505D01*
G03X350397Y1592532I2798J153D01*
G03X353222Y1592110I1769J2173D01*
G03X354191Y1592769I-1057J2595D01*
G02X355914Y1592133I724J-691D01*
G01Y1574569D01*
G02X354232Y1573892I-999J55D01*
G01X343417Y1584707D01*
X343416Y1588410D01*
Y1591906D01*
G02X343651Y1592330I500J0D01*
G03X344626Y1596045I-1486J2375D01*
G03X343879Y1596922I-2461J-1340D01*
G03X339441Y1595365I-1714J-2217D01*
G01X339402Y1595204D01*
X339237Y1595066D01*
G02X338416Y1595450I-321J384D01*
G01Y1596906D01*
G02X338651Y1597330I500J0D01*
G03X339879Y1600400I-1486J2375D01*
G03X339699Y1600901I-2715J-693D01*
G03X339355Y1601453I-2534J-1196D01*
G03X335531Y1601982I-2190J-1748D01*
G02X333948Y1602740I-584J812D01*
G01Y1606670D01*
G02X335531Y1607428I999J-54D01*
G03X339942Y1609328I1634J2276D01*
G03X339531Y1611207I-2777J377D01*
G02X340336Y1612718I860J512D01*
G01X343994D01*
G02X344799Y1611207I-55J-999D01*
G03X349531I2366J-1502D01*
G02X350336Y1612718I860J512D01*
G01X352176D01*
G02X352529Y1612571I-1J-500D01*
G01X353896Y1611204D01*
X354298Y1610802D01*
G02X354440Y1610388I-354J-353D01*
G01X354434Y1610335D01*
X354428Y1610310D01*
G03X359860Y1608935I2737J-605D01*
G01Y1608937D01*
G02X360694Y1609153I481J-138D01*
G01X360914Y1608933D01*
Y1607504D01*
G02X360679Y1607080I-500J0D01*
G03X363651I1486J-2375D01*
G02X363416Y1607504I265J424D01*
G01Y1609970D01*
X358074Y1615313D01*
X355793Y1617594D01*
X334314D01*
X329072Y1612352D01*
Y1584640D01*
X341922Y1571790D01*
X341958Y1571666D01*
G03X342629Y1570792I1444J414D01*
G01X388620Y1524801D01*
Y1412362D01*
X372904Y1396646D01*
X346351D01*
G02X346619Y1397366I999J38D01*
G01X351027Y1401774D01*
X351144Y1401811D01*
G03X352122Y1402789I-454J1432D01*
G01X352159Y1402906D01*
X366962Y1417709D01*
Y1427150D01*
G02X368672Y1427853I1000J-1D01*
G03X379789Y1430793I4713J4666D01*
G03X371466Y1438869I-6404J1727D01*
G03X366965Y1434186I1919J-6349D01*
G02X365302Y1433776I-955J297D01*
G01X363293Y1435785D01*
X358585Y1440492D01*
X341183D01*
X338299Y1437609D01*
X338263Y1437573D01*
X338181Y1437491D01*
X337964Y1437415D01*
X337795Y1437436D01*
X337770Y1437442D01*
G03X335847Y1432232I-606J-2736D01*
G02X336084Y1430643I-470J-882D01*
G01X331520Y1426079D01*
Y1423023D01*
X316177Y1407680D01*
X180596D01*
X174604Y1413672D01*
X155604D01*
X153718Y1411786D01*
X149401Y1407468D01*
G02X149048Y1407322I-353J354D01*
G01X144178D01*
G02X143305Y1408698I54J999D01*
G03X136535I-3385J1499D01*
G02X135662Y1407322I-927J-377D01*
G01X124178D01*
G02X123305Y1408698I54J999D01*
G03X116535I-3385J1499D01*
G02X115662Y1407322I-927J-377D01*
G01X106681D01*
X96220Y1396862D01*
X96096Y1396826D01*
G03X95066Y1395796I414J-1444D01*
G01X95030Y1395672D01*
X89366Y1390008D01*
G02X87684Y1390685I-683J732D01*
G01Y1458024D01*
X116520Y1486860D01*
Y1606208D01*
G02X118031Y1607013I999J-55D01*
G03Y1613381I1889J3184D01*
G02X116520Y1614186I-512J860D01*
G01Y1616208D01*
G02X118031Y1617013I999J-55D01*
G03Y1623381I1889J3184D01*
G02X116520Y1624186I-512J860D01*
G01Y1626208D01*
G02X118031Y1627013I999J-55D01*
G03Y1633381I1889J3184D01*
G02X116520Y1634186I-512J860D01*
G01Y1636208D01*
G02X118031Y1637013I999J-55D01*
G03Y1643381I1889J3184D01*
G02X116520Y1644186I-512J860D01*
G01Y1646208D01*
G02X118031Y1647013I999J-55D01*
G03Y1653381I1889J3184D01*
G02X116520Y1654186I-512J860D01*
G01Y1656208D01*
G02X118031Y1657013I999J-55D01*
G03Y1663381I1889J3184D01*
G02X116520Y1664186I-512J860D01*
G01Y1666208D01*
G02X118031Y1667013I999J-55D01*
G03Y1673381I1889J3184D01*
G02X116520Y1674186I-512J860D01*
G01Y1676208D01*
G02X118031Y1677013I999J-55D01*
G03Y1683381I1889J3184D01*
G02X116520Y1684186I-512J860D01*
G01Y1686208D01*
G02X118031Y1687013I999J-55D01*
G03Y1693381I1889J3184D01*
G02X116520Y1694186I-512J860D01*
G01Y1696208D01*
G02X118031Y1697013I999J-55D01*
G03Y1703381I1889J3184D01*
G02X116520Y1704186I-512J860D01*
G01Y1706208D01*
G02X118031Y1707013I999J-55D01*
G03Y1713381I1889J3184D01*
G02X116520Y1714186I-512J860D01*
G01Y1716208D01*
G02X118031Y1717013I999J-55D01*
G03X123612Y1720476I1889J3184D01*
G03X121029Y1723729I-3692J-279D01*
G02X120623Y1725356I326J946D01*
G01X121033Y1725766D01*
X122422Y1727155D01*
G02X122775Y1727302I354J-353D01*
G01X173312D01*
X185832Y1739822D01*
X355537D01*
X396078Y1780363D01*
Y1902355D01*
X380883Y1917551D01*
X380847Y1917675D01*
G03X380176Y1918549I-1444J-414D01*
G01X363622Y1935103D01*
Y1942046D01*
G02X363826Y1942449I500J0D01*
G03X364773Y1945730I-1661J2257D01*
G03X362975Y1947389I-2609J-1023D01*
G02X362619Y1947867I144J479D01*
G37*
G36*
G01X75158Y1059160D02*
G02X74842Y1059307I40J499D01*
G01X43766Y1090383D01*
Y1093372D01*
X42073Y1095065D01*
X41630Y1095508D01*
X38107Y1099030D01*
X36551D01*
G02X35658Y1100325I63J999D01*
G03X34802Y1103038I-2391J737D01*
G02X34684Y1104510I613J790D01*
G01X44248Y1114074D01*
X89917D01*
X105314Y1129471D01*
G02X106994Y1128995I707J-707D01*
G03X108759Y1130760I1474J291D01*
G02X108283Y1132440I231J973D01*
G01X117060Y1141217D01*
Y1257847D01*
G02X118455Y1258765I1000J0D01*
G03Y1265565I1465J3400D01*
G02X117060Y1266483I-395J918D01*
G01Y1267847D01*
G02X118455Y1268765I1000J0D01*
G03Y1275565I1465J3400D01*
G02X117060Y1276483I-395J918D01*
G01Y1277847D01*
G02X118455Y1278765I1000J0D01*
G03Y1285565I1465J3400D01*
G02X117060Y1286483I-395J918D01*
G01Y1287847D01*
G02X118455Y1288765I1000J0D01*
G03Y1295565I1465J3400D01*
G02X117060Y1296483I-395J918D01*
G01Y1297847D01*
G02X118455Y1298765I1000J0D01*
G03Y1305565I1465J3400D01*
G02X117060Y1306483I-395J918D01*
G01Y1307847D01*
G02X118455Y1308765I1000J0D01*
G03Y1315565I1465J3400D01*
G02X117060Y1316483I-395J918D01*
G01Y1317847D01*
G02X118455Y1318765I1000J0D01*
G03Y1325565I1465J3400D01*
G02X117060Y1326483I-395J918D01*
G01Y1327847D01*
G02X118455Y1328765I1000J0D01*
G03Y1335565I1465J3400D01*
G02X117060Y1336483I-395J918D01*
G01Y1337847D01*
G02X118455Y1338765I1000J0D01*
G03Y1345565I1465J3400D01*
G02X117060Y1346483I-395J918D01*
G01Y1347847D01*
G02X118455Y1348765I1000J0D01*
G03Y1355565I1465J3400D01*
G02X117060Y1356483I-395J918D01*
G01Y1357847D01*
G02X118455Y1358765I1000J0D01*
G03Y1365565I1465J3400D01*
G02X117060Y1366483I-395J918D01*
G01Y1367847D01*
G02X118455Y1368765I1000J0D01*
G03X122853Y1369906I1465J3400D01*
G03X122991Y1370098I-2935J2255D01*
G03X120354Y1375841I-3071J2067D01*
G01X120182Y1375862D01*
X120059Y1375984D01*
G02Y1376692I354J354D01*
G01X120662Y1377294D01*
X169496D01*
X177636Y1369154D01*
X238335D01*
X311628Y1295861D01*
Y1271321D01*
X317328Y1265621D01*
Y1244293D01*
X354430Y1207191D01*
Y1176640D01*
X325306Y1147516D01*
Y1127208D01*
X325244Y1127095D01*
G03Y1125641I1314J-727D01*
G01X325306Y1125528D01*
Y1110137D01*
X335913Y1099530D01*
X335914Y1098001D01*
Y1087504D01*
G02X335679Y1087080I-500J0D01*
G03X334408Y1084206I1486J-2375D01*
G03X334532Y1083746I2757J497D01*
G03X335550Y1082415I2633J959D01*
G03X339889Y1084047I1615J2290D01*
G01X339928Y1084208D01*
X340092Y1084345D01*
G02X340913Y1083962I321J-383D01*
G01Y1083930D01*
X340914Y1083756D01*
Y1082504D01*
G02X340679Y1082080I-500J0D01*
G03X339408Y1079206I1486J-2375D01*
G03X339532Y1078746I2757J497D01*
G03X340550Y1077415I2633J959D01*
G03X344922Y1079197I1616J2290D01*
G02X345914Y1079106I492J-90D01*
G01Y1077504D01*
G02X345679Y1077080I-500J0D01*
G03X348651I1486J-2375D01*
G02X348416Y1077504I265J424D01*
G01Y1079216D01*
X348580Y1079380D01*
G02X349287I353J-354D01*
G01X349392Y1079275D01*
X349423Y1079129D01*
G03X350612Y1077373I2742J576D01*
G03X354419Y1078040I1553J2332D01*
G03X354466Y1078106I-2259J1658D01*
G03X352272Y1082505I-2301J1599D01*
G02X351790Y1083005I18J500D01*
G01Y1100876D01*
X347923Y1104744D01*
X347437Y1105230D01*
X345578Y1107089D01*
X345543Y1107213D01*
G03X344514Y1108242I-1444J-415D01*
G01X344390Y1108277D01*
X336632Y1116035D01*
Y1145777D01*
X363668Y1172813D01*
Y1207581D01*
X331330Y1239919D01*
Y1244082D01*
G02X331830Y1244582I500J0D01*
G01X333012D01*
X370272Y1207322D01*
Y1205565D01*
X370209Y1205452D01*
G03Y1203998I1314J-727D01*
G01X370272Y1203885D01*
Y1152675D01*
X387724Y1135222D01*
Y1080001D01*
X371474Y1063750D01*
X283391D01*
X278801Y1059160D01*
X144111D01*
G02X143269Y1060587I63J999D01*
G03X136571I-3349J1578D01*
G02X135729Y1059160I-905J-428D01*
G01X124111D01*
G02X123269Y1060587I63J999D01*
G03X116571I-3349J1578D01*
G02X115729Y1059160I-905J-428D01*
G01X85200D01*
G02X84264Y1060117I64J999D01*
G03X81262I-1501J-66D01*
G02X80326Y1059160I-1000J42D01*
G01X75158D01*
G37*
G36*
G01X36653Y1233028D02*
G02X35686Y1234283I0J1000D01*
G03X34982Y1236742I-2419J638D01*
G01X34907Y1236814D01*
X34825Y1237003D01*
Y1237106D01*
G02X35325Y1237606I500J0D01*
G01X35384D01*
X44626Y1246848D01*
Y1247876D01*
X66192Y1269442D01*
Y1305355D01*
G02X67342Y1306344I1000J1D01*
G03Y1309314I226J1485D01*
G02X66192Y1310303I-150J988D01*
G01Y1457334D01*
X76680Y1467823D01*
G02X78388Y1467115I708J-707D01*
G01Y1383672D01*
X77122Y1382407D01*
Y1262087D01*
X48063Y1233028D01*
X36653D01*
G37*
G36*
G01X359942Y1260081D02*
G03X356536Y1262436I-2777J-376D01*
G02X356070Y1262570I-112J487D01*
G01X352058Y1266582D01*
X336002D01*
X332184Y1262764D01*
G02X331330Y1263117I-354J353D01*
G01Y1263290D01*
X319880Y1274740D01*
Y1279838D01*
G02X321294Y1280749I1000J1D01*
G03Y1283423I684J1337D01*
G02X319880Y1284334I-414J910D01*
G01Y1299280D01*
X242941Y1376219D01*
X181276D01*
X174186Y1383309D01*
Y1386063D01*
X174604Y1386480D01*
X377118D01*
X397801Y1407163D01*
G02X399508Y1406456I707J-707D01*
G01Y954973D01*
X398447Y953912D01*
X397777D01*
X369842Y981847D01*
X314425D01*
X311295Y984976D01*
X253820Y1042451D01*
Y1048032D01*
X254513Y1048725D01*
G02X255476Y1049454I963J-271D01*
G01X317695D01*
X318761Y1048388D01*
X327657D01*
X328723Y1049454D01*
X333216D01*
G02X334199Y1048634I0J-1000D01*
G03X337155I1478J270D01*
G02X338138Y1049454I983J-180D01*
G01X343152D01*
G02X344121Y1048210I0J-1000D01*
G03X347035I1457J-366D01*
G02X348004Y1049454I969J244D01*
G01X370745D01*
X396728Y1075437D01*
X396895Y1075605D01*
Y1140600D01*
X388068Y1149427D01*
Y1179001D01*
X388130Y1179114D01*
G03Y1180568I-1314J727D01*
G01X388068Y1180681D01*
Y1226428D01*
X363539Y1250956D01*
X362759D01*
G02X362259Y1251456I0J500D01*
G01Y1251638D01*
X362490Y1251916D01*
X362669Y1251948D01*
G03X361536Y1257436I-504J2757D01*
G02X361070Y1257570I-112J487D01*
G01X360825Y1257815D01*
G02X359886Y1259036I36J999D01*
G03X359942Y1260081I-2721J670D01*
G37*
%LPC*%
G75*
G36*
G01X168075Y311105D02*
G03X166875I-600J-800D01*
G02Y313509I-900J1202D01*
G03X168075I600J800D01*
G02Y311105I900J-1202D01*
G37*
G36*
G01Y302666D02*
G03X166875I-600J-800D01*
G02Y305070I-900J1202D01*
G03X168075I600J800D01*
G02Y302666I900J-1202D01*
G37*
G36*
G01Y294938D02*
G03X166875I-600J-800D01*
G02Y297342I-900J1202D01*
G03X168075I600J800D01*
G02Y294938I900J-1202D01*
G37*
G36*
G01Y285601D02*
G03X166875I-600J-800D01*
G02Y288005I-900J1202D01*
G03X168075I600J800D01*
G02Y285601I900J-1202D01*
G37*
G36*
G01Y275096D02*
G03X166875I-600J-800D01*
G02Y277500I-900J1202D01*
G03X168075I600J800D01*
G02Y275096I900J-1202D01*
G37*
G36*
G01X263696Y266986D02*
G03X262496I-600J-800D01*
G02Y269390I-900J1202D01*
G03X263696I600J800D01*
G02Y266986I900J-1202D01*
G37*
G36*
G01X254918D02*
G03X253718I-600J-800D01*
G02Y269390I-900J1202D01*
G03X254918I600J800D01*
G02Y266986I900J-1202D01*
G37*
G36*
G01X168075Y264581D02*
G03X166875I-600J-800D01*
G02Y266985I-900J1202D01*
G03X168075I600J800D01*
G02Y264581I900J-1202D01*
G37*
G36*
G01X263696Y258547D02*
G03X262496I-600J-800D01*
G02Y260951I-900J1202D01*
G03X263696I600J800D01*
G02Y258547I900J-1202D01*
G37*
G36*
G01X254918D02*
G03X253718I-600J-800D01*
G02Y260951I-900J1202D01*
G03X254918I600J800D01*
G02Y258547I900J-1202D01*
G37*
G36*
G01X263696Y250819D02*
G03X262496I-600J-800D01*
G02Y253223I-900J1202D01*
G03X263696I600J800D01*
G02Y250819I900J-1202D01*
G37*
G36*
G01X254918D02*
G03X253718I-600J-800D01*
G02Y253223I-900J1202D01*
G03X254918I600J800D01*
G02Y250819I900J-1202D01*
G37*
G36*
G01X263696Y241482D02*
G03X262496I-600J-800D01*
G02Y243886I-900J1202D01*
G03X263696I600J800D01*
G02Y241482I900J-1202D01*
G37*
G36*
G01X254918D02*
G03X253718I-600J-800D01*
G02Y243886I-900J1202D01*
G03X254918I600J800D01*
G02Y241482I900J-1202D01*
G37*
G36*
G01X263696Y230977D02*
G03X262496I-600J-800D01*
G02Y233381I-900J1202D01*
G03X263696I600J800D01*
G02Y230977I900J-1202D01*
G37*
G36*
G01X254918D02*
G03X253718I-600J-800D01*
G02Y233381I-900J1202D01*
G03X254918I600J800D01*
G02Y230977I900J-1202D01*
G37*
G36*
G01X263696Y220462D02*
G03X262496I-600J-800D01*
G02Y222866I-900J1202D01*
G03X263696I600J800D01*
G02Y220462I900J-1202D01*
G37*
G36*
G01X254918D02*
G03X253718I-600J-800D01*
G02Y222866I-900J1202D01*
G03X254918I600J800D01*
G02Y220462I900J-1202D01*
G37*
G36*
G01X169982Y202727D02*
G02X170002Y202205I-6597J-514D01*
G02X156766I-6618J0D01*
G02X169982Y202727I6618J0D01*
G37*
G36*
G01X258063Y172231D02*
G03Y171031I800J-600D01*
G02X255659I-1202J-900D01*
G03Y172231I-800J600D01*
G02X258063I1202J900D01*
G37*
G36*
G01X249285D02*
G03Y171031I800J-600D01*
G02X246881I-1202J-900D01*
G03Y172231I-800J600D01*
G02X249285I1202J900D01*
G37*
G36*
G01X239943D02*
G03Y171031I800J-600D01*
G02X237539I-1202J-900D01*
G03Y172231I-800J600D01*
G02X239943I1202J900D01*
G37*
G36*
G01X228902D02*
G03Y171031I800J-600D01*
G02X226498I-1202J-900D01*
G03Y172231I-800J600D01*
G02X228902I1202J900D01*
G37*
G36*
G01X218934D02*
G03Y171031I800J-600D01*
G02X216530I-1202J-900D01*
G03Y172231I-800J600D01*
G02X218934I1202J900D01*
G37*
G36*
G01X258063Y163792D02*
G03Y162592I800J-600D01*
G02X255659I-1202J-900D01*
G03Y163792I-800J600D01*
G02X258063I1202J900D01*
G37*
G36*
G01X249285D02*
G03Y162592I800J-600D01*
G02X246881I-1202J-900D01*
G03Y163792I-800J600D01*
G02X249285I1202J900D01*
G37*
G36*
G01X239943D02*
G03Y162592I800J-600D01*
G02X237539I-1202J-900D01*
G03Y163792I-800J600D01*
G02X239943I1202J900D01*
G37*
G36*
G01X228902D02*
G03Y162592I800J-600D01*
G02X226498I-1202J-900D01*
G03Y163792I-800J600D01*
G02X228902I1202J900D01*
G37*
G36*
G01X218934D02*
G03Y162592I800J-600D01*
G02X216530I-1202J-900D01*
G03Y163792I-800J600D01*
G02X218934I1202J900D01*
G37*
G36*
G01X258063Y156064D02*
G03Y154864I800J-600D01*
G02X255659I-1202J-900D01*
G03Y156064I-800J600D01*
G02X258063I1202J900D01*
G37*
G36*
G01X249285D02*
G03Y154864I800J-600D01*
G02X246881I-1202J-900D01*
G03Y156064I-800J600D01*
G02X249285I1202J900D01*
G37*
G36*
G01X239943D02*
G03Y154864I800J-600D01*
G02X237539I-1202J-900D01*
G03Y156064I-800J600D01*
G02X239943I1202J900D01*
G37*
G36*
G01X228902D02*
G03Y154864I800J-600D01*
G02X226498I-1202J-900D01*
G03Y156064I-800J600D01*
G02X228902I1202J900D01*
G37*
G36*
G01X218934D02*
G03Y154864I800J-600D01*
G02X216530I-1202J-900D01*
G03Y156064I-800J600D01*
G02X218934I1202J900D01*
G37*
G36*
G01X289304Y67549D02*
G03Y66349I800J-600D01*
G02X286900I-1202J-900D01*
G03Y67549I-800J600D01*
G02X289304I1202J900D01*
G37*
G36*
G01X280956D02*
G03Y66349I800J-600D01*
G02X278552I-1202J-900D01*
G03Y67549I-800J600D01*
G02X280956I1202J900D01*
G37*
G36*
G01X272774D02*
G03Y66349I800J-600D01*
G02X270370I-1202J-900D01*
G03Y67549I-800J600D01*
G02X272774I1202J900D01*
G37*
G36*
G01X265306D02*
G03Y66349I800J-600D01*
G02X262902I-1202J-900D01*
G03Y67549I-800J600D01*
G02X265306I1202J900D01*
G37*
G36*
G01X257768D02*
G03Y66349I800J-600D01*
G02X255364I-1202J-900D01*
G03Y67549I-800J600D01*
G02X257768I1202J900D01*
G37*
G36*
G01X289304Y57044D02*
G03Y55844I800J-600D01*
G02X286900I-1202J-900D01*
G03Y57044I-800J600D01*
G02X289304I1202J900D01*
G37*
G36*
G01X280956D02*
G03Y55844I800J-600D01*
G02X278552I-1202J-900D01*
G03Y57044I-800J600D01*
G02X280956I1202J900D01*
G37*
G36*
G01X272774D02*
G03Y55844I800J-600D01*
G02X270370I-1202J-900D01*
G03Y57044I-800J600D01*
G02X272774I1202J900D01*
G37*
G36*
G01X265306D02*
G03Y55844I800J-600D01*
G02X262902I-1202J-900D01*
G03Y57044I-800J600D01*
G02X265306I1202J900D01*
G37*
G36*
G01X257768D02*
G03Y55844I800J-600D01*
G02X255364I-1202J-900D01*
G03Y57044I-800J600D01*
G02X257768I1202J900D01*
G37*
G36*
G01X289304Y47672D02*
G03Y46472I800J-600D01*
G02X286900I-1202J-900D01*
G03Y47672I-800J600D01*
G02X289304I1202J900D01*
G37*
G36*
G01X280956D02*
G03Y46472I800J-600D01*
G02X278552I-1202J-900D01*
G03Y47672I-800J600D01*
G02X280956I1202J900D01*
G37*
G36*
G01X272774D02*
G03Y46472I800J-600D01*
G02X270370I-1202J-900D01*
G03Y47672I-800J600D01*
G02X272774I1202J900D01*
G37*
G36*
G01X265306D02*
G03Y46472I800J-600D01*
G02X262902I-1202J-900D01*
G03Y47672I-800J600D01*
G02X265306I1202J900D01*
G37*
G36*
G01X257768D02*
G03Y46472I800J-600D01*
G02X255364I-1202J-900D01*
G03Y47672I-800J600D01*
G02X257768I1202J900D01*
G37*
G36*
G01X169982Y27727D02*
G02X170002Y27205I-6597J-514D01*
G02X156766I-6618J0D01*
G02X169982Y27727I6618J0D01*
G37*
G36*
G01X123160Y69862D02*
G02X116680I-3240J-1791D01*
G03X115805Y71346I-875J484D01*
G01X115136D01*
X114133Y70342D01*
X107263D01*
G02Y74146I0J1902D01*
G01X112557D01*
X113560Y75148D01*
X115629D01*
G03X116542Y76557I0J1000D01*
G02X123298I3378J1514D01*
G03X124211Y75148I913J-409D01*
G01X127048D01*
X136670Y84770D01*
X136787D01*
G03X137287Y85270I0J500D01*
G01Y85461D01*
X137160Y85604D01*
G02X143149Y86260I2760J2467D01*
G03X144021Y84770I872J-490D01*
G01X155733D01*
X156169Y84335D01*
G03X156876I353J353D01*
G01X156959Y84418D01*
X157034Y84640D01*
X157017Y84757D01*
G02X158901Y86918I1884J259D01*
G01X159459D01*
G03X159959Y87418I0J500D01*
G01Y87507D01*
X159929Y87591D01*
G02X159900Y88538I1410J517D01*
G03X159132Y89806I-958J286D01*
G02X160856Y90851I285J1475D01*
G03X161624Y89583I958J-286D01*
G02X162837Y87994I-285J-1475D01*
G03X163834Y86918I997J-76D01*
G01X197817D01*
X235662Y124764D01*
X250745D01*
X255602Y129621D01*
G02X258292Y126931I1345J-1345D01*
G01X253720Y122360D01*
G03Y121653I354J-353D01*
G01X258470Y116904D01*
G02X255780Y114214I-1345J-1345D01*
G01X252291Y117704D01*
X238588D01*
X200743Y79858D01*
X155266D01*
X154157Y80968D01*
X144223D01*
G03X143308Y79564I0J-1000D01*
G02X136373Y77010I-3388J-1493D01*
G03X134708Y77430I-958J-287D01*
G01X128624Y71346D01*
X124035D01*
G03X123160Y69862I0J-1000D01*
G37*
G36*
G01X65354Y94272D02*
G02X44667Y114960I0J20687D01*
G02X65351Y135647I20687J0D01*
G01X65357D01*
G02X86041Y114960I-3J-20687D01*
G02X65354Y94272I-20687J-1D01*
G37*
G36*
G01X170004Y727205D02*
G02X156767Y727182I-6619J0D01*
G02X169983Y727726I6618J30D01*
G02X169986Y727689I-6594J-553D01*
G02X170004Y727205I-6600J-488D01*
G37*
G36*
G01Y552205D02*
G02X156767Y552182I-6619J0D01*
G02X169983Y552726I6618J30D01*
G02X169986Y552689I-6594J-553D01*
G02X170004Y552205I-6600J-488D01*
G37*
G36*
G01X276499Y989351D02*
G03X275299I-600J-800D01*
G02Y991755I-900J1202D01*
G03X276499I600J800D01*
G02Y989351I900J-1202D01*
G37*
G36*
G01X264721D02*
G03X263521I-600J-800D01*
G02Y991755I-900J1202D01*
G03X264721I600J800D01*
G02Y989351I900J-1202D01*
G37*
G36*
G01X276499Y980912D02*
G03X275299I-600J-800D01*
G02Y983316I-900J1202D01*
G03X276499I600J800D01*
G02Y980912I900J-1202D01*
G37*
G36*
G01X264721D02*
G03X263521I-600J-800D01*
G02Y983316I-900J1202D01*
G03X264721I600J800D01*
G02Y980912I900J-1202D01*
G37*
G36*
G01X276499Y973184D02*
G03X275299I-600J-800D01*
G02Y975588I-900J1202D01*
G03X276499I600J800D01*
G02Y973184I900J-1202D01*
G37*
G36*
G01X264721D02*
G03X263521I-600J-800D01*
G02Y975588I-900J1202D01*
G03X264721I600J800D01*
G02Y973184I900J-1202D01*
G37*
G36*
G01X276644Y965904D02*
G03X275444I-600J-800D01*
G02Y968308I-900J1202D01*
G03X276644I600J800D01*
G02Y965904I900J-1202D01*
G37*
G36*
G01X264866D02*
G03X263666I-600J-800D01*
G02Y968308I-900J1202D01*
G03X264866I600J800D01*
G02Y965904I900J-1202D01*
G37*
G36*
G01X276644Y958657D02*
G03X275444I-600J-800D01*
G02Y961061I-900J1202D01*
G03X276644I600J800D01*
G02Y958657I900J-1202D01*
G37*
G36*
G01X264866D02*
G03X263666I-600J-800D01*
G02Y961061I-900J1202D01*
G03X264866I600J800D01*
G02Y958657I900J-1202D01*
G37*
G36*
G01X276644Y948142D02*
G03X275444I-600J-800D01*
G02Y950546I-900J1202D01*
G03X276644I600J800D01*
G02Y948142I900J-1202D01*
G37*
G36*
G01X264866D02*
G03X263666I-600J-800D01*
G02Y950546I-900J1202D01*
G03X264866I600J800D01*
G02Y948142I900J-1202D01*
G37*
G36*
G01X169982Y902727D02*
G02X170003Y902205I-6597J-527D01*
G02X156766I-6618J0D01*
G02X169982Y902727I6618J0D01*
G37*
G36*
G01X252274Y870124D02*
G03X251074I-600J-800D01*
G02Y872528I-900J1202D01*
G03X252274I600J800D01*
G02Y870124I900J-1202D01*
G37*
G36*
G01X240496D02*
G03X239296I-600J-800D01*
G02Y872528I-900J1202D01*
G03X240496I600J800D01*
G02Y870124I900J-1202D01*
G37*
G36*
G01X252274Y861685D02*
G03X251074I-600J-800D01*
G02Y864089I-900J1202D01*
G03X252274I600J800D01*
G02Y861685I900J-1202D01*
G37*
G36*
G01X240496D02*
G03X239296I-600J-800D01*
G02Y864089I-900J1202D01*
G03X240496I600J800D01*
G02Y861685I900J-1202D01*
G37*
G36*
G01X252274Y853957D02*
G03X251074I-600J-800D01*
G02Y856361I-900J1202D01*
G03X252274I600J800D01*
G02Y853957I900J-1202D01*
G37*
G36*
G01X240496D02*
G03X239296I-600J-800D01*
G02Y856361I-900J1202D01*
G03X240496I600J800D01*
G02Y853957I900J-1202D01*
G37*
G36*
G01X257121Y769747D02*
G03X255921I-600J-800D01*
G02Y772151I-900J1202D01*
G03X257121I600J800D01*
G02Y769747I900J-1202D01*
G37*
G36*
G01X246080D02*
G03X244880I-600J-800D01*
G02Y772151I-900J1202D01*
G03X246080I600J800D01*
G02Y769747I900J-1202D01*
G37*
G36*
G01X236112D02*
G03X234912I-600J-800D01*
G02Y772151I-900J1202D01*
G03X236112I600J800D01*
G02Y769747I900J-1202D01*
G37*
G36*
G01X257121Y761308D02*
G03X255921I-600J-800D01*
G02Y763712I-900J1202D01*
G03X257121I600J800D01*
G02Y761308I900J-1202D01*
G37*
G36*
G01X246080D02*
G03X244880I-600J-800D01*
G02Y763712I-900J1202D01*
G03X246080I600J800D01*
G02Y761308I900J-1202D01*
G37*
G36*
G01X236112D02*
G03X234912I-600J-800D01*
G02Y763712I-900J1202D01*
G03X236112I600J800D01*
G02Y761308I900J-1202D01*
G37*
G36*
G01X257121Y753580D02*
G03X255921I-600J-800D01*
G02Y755984I-900J1202D01*
G03X257121I600J800D01*
G02Y753580I900J-1202D01*
G37*
G36*
G01X246080D02*
G03X244880I-600J-800D01*
G02Y755984I-900J1202D01*
G03X246080I600J800D01*
G02Y753580I900J-1202D01*
G37*
G36*
G01X236112D02*
G03X234912I-600J-800D01*
G02Y755984I-900J1202D01*
G03X236112I600J800D01*
G02Y753580I900J-1202D01*
G37*
G36*
G01X317287Y696065D02*
G03X316087I-600J-800D01*
G02Y698469I-900J1202D01*
G03X317287I600J800D01*
G02Y696065I900J-1202D01*
G37*
G36*
G01X306246D02*
G03X305046I-600J-800D01*
G02Y698469I-900J1202D01*
G03X306246I600J800D01*
G02Y696065I900J-1202D01*
G37*
G36*
G01X317287Y687626D02*
G03X316087I-600J-800D01*
G02Y690030I-900J1202D01*
G03X317287I600J800D01*
G02Y687626I900J-1202D01*
G37*
G36*
G01X306246D02*
G03X305046I-600J-800D01*
G02Y690030I-900J1202D01*
G03X306246I600J800D01*
G02Y687626I900J-1202D01*
G37*
G36*
G01X317287Y679898D02*
G03X316087I-600J-800D01*
G02Y682302I-900J1202D01*
G03X317287I600J800D01*
G02Y679898I900J-1202D01*
G37*
G36*
G01X306246D02*
G03X305046I-600J-800D01*
G02Y682302I-900J1202D01*
G03X306246I600J800D01*
G02Y679898I900J-1202D01*
G37*
G36*
G01X317287Y670561D02*
G03X316087I-600J-800D01*
G02Y672965I-900J1202D01*
G03X317287I600J800D01*
G02Y670561I900J-1202D01*
G37*
G36*
G01X306246D02*
G03X305046I-600J-800D01*
G02Y672965I-900J1202D01*
G03X306246I600J800D01*
G02Y670561I900J-1202D01*
G37*
G36*
G01X317287Y660056D02*
G03X316087I-600J-800D01*
G02Y662460I-900J1202D01*
G03X317287I600J800D01*
G02Y660056I900J-1202D01*
G37*
G36*
G01X306246D02*
G03X305046I-600J-800D01*
G02Y662460I-900J1202D01*
G03X306246I600J800D01*
G02Y660056I900J-1202D01*
G37*
G36*
G01X317287Y651255D02*
G03X316087I-600J-800D01*
G02Y653659I-900J1202D01*
G03X317287I600J800D01*
G02Y651255I900J-1202D01*
G37*
G36*
G01X306246D02*
G03X305046I-600J-800D01*
G02Y653659I-900J1202D01*
G03X306246I600J800D01*
G02Y651255I900J-1202D01*
G37*
G36*
G01X159372Y648381D02*
G03X158172I-600J-800D01*
G02Y650785I-900J1202D01*
G03X159372I600J800D01*
G02Y648381I900J-1202D01*
G37*
G36*
G01Y639942D02*
G03X158172I-600J-800D01*
G02Y642346I-900J1202D01*
G03X159372I600J800D01*
G02Y639942I900J-1202D01*
G37*
G36*
G01Y632214D02*
G03X158172I-600J-800D01*
G02Y634618I-900J1202D01*
G03X159372I600J800D01*
G02Y632214I900J-1202D01*
G37*
G36*
G01Y622877D02*
G03X158172I-600J-800D01*
G02Y625281I-900J1202D01*
G03X159372I600J800D01*
G02Y622877I900J-1202D01*
G37*
G36*
G01X278044Y616247D02*
G03X276844I-600J-800D01*
G02Y618651I-900J1202D01*
G03X278044I600J800D01*
G02Y616247I900J-1202D01*
G37*
G36*
G01X266266D02*
G03X265066I-600J-800D01*
G02Y618651I-900J1202D01*
G03X266266I600J800D01*
G02Y616247I900J-1202D01*
G37*
G36*
G01X159372Y612372D02*
G03X158172I-600J-800D01*
G02Y614776I-900J1202D01*
G03X159372I600J800D01*
G02Y612372I900J-1202D01*
G37*
G36*
G01X278044Y607808D02*
G03X276844I-600J-800D01*
G02Y610212I-900J1202D01*
G03X278044I600J800D01*
G02Y607808I900J-1202D01*
G37*
G36*
G01X266266D02*
G03X265066I-600J-800D01*
G02Y610212I-900J1202D01*
G03X266266I600J800D01*
G02Y607808I900J-1202D01*
G37*
G36*
G01X159372Y603571D02*
G03X158172I-600J-800D01*
G02Y605975I-900J1202D01*
G03X159372I600J800D01*
G02Y603571I900J-1202D01*
G37*
G36*
G01X278044Y600080D02*
G03X276844I-600J-800D01*
G02Y602484I-900J1202D01*
G03X278044I600J800D01*
G02Y600080I900J-1202D01*
G37*
G36*
G01X266266D02*
G03X265066I-600J-800D01*
G02Y602484I-900J1202D01*
G03X266266I600J800D01*
G02Y600080I900J-1202D01*
G37*
G36*
G01X278044Y590743D02*
G03X276844I-600J-800D01*
G02Y593147I-900J1202D01*
G03X278044I600J800D01*
G02Y590743I900J-1202D01*
G37*
G36*
G01X266266D02*
G03X265066I-600J-800D01*
G02Y593147I-900J1202D01*
G03X266266I600J800D01*
G02Y590743I900J-1202D01*
G37*
G36*
G01X278044Y580238D02*
G03X276844I-600J-800D01*
G02Y582642I-900J1202D01*
G03X278044I600J800D01*
G02Y580238I900J-1202D01*
G37*
G36*
G01X266266D02*
G03X265066I-600J-800D01*
G02Y582642I-900J1202D01*
G03X266266I600J800D01*
G02Y580238I900J-1202D01*
G37*
G36*
G01X278044Y571437D02*
G03X276844I-600J-800D01*
G02Y573841I-900J1202D01*
G03X278044I600J800D01*
G02Y571437I900J-1202D01*
G37*
G36*
G01X266266D02*
G03X265066I-600J-800D01*
G02Y573841I-900J1202D01*
G03X266266I600J800D01*
G02Y571437I900J-1202D01*
G37*
G36*
G01X315891Y531669D02*
G03X314691I-600J-800D01*
G02Y534073I-900J1202D01*
G03X315891I600J800D01*
G02Y531669I900J-1202D01*
G37*
G36*
G01X324239Y531597D02*
G03X323039I-600J-800D01*
G02Y534001I-900J1202D01*
G03X324239I600J800D01*
G02Y531597I900J-1202D01*
G37*
G36*
G01X291669Y531560D02*
G03X290469I-600J-800D01*
G02Y533964I-900J1202D01*
G03X291669I600J800D01*
G02Y531560I900J-1202D01*
G37*
G36*
G01X307066Y531384D02*
G03X305866I-600J-800D01*
G02Y533788I-900J1202D01*
G03X307066I600J800D01*
G02Y531384I900J-1202D01*
G37*
G36*
G01X299637Y531274D02*
G03X298437I-600J-800D01*
G02Y533678I-900J1202D01*
G03X299637I600J800D01*
G02Y531274I900J-1202D01*
G37*
G36*
G01X315891Y523230D02*
G03X314691I-600J-800D01*
G02Y525634I-900J1202D01*
G03X315891I600J800D01*
G02Y523230I900J-1202D01*
G37*
G36*
G01X324239Y523158D02*
G03X323039I-600J-800D01*
G02Y525562I-900J1202D01*
G03X324239I600J800D01*
G02Y523158I900J-1202D01*
G37*
G36*
G01X291669Y523121D02*
G03X290469I-600J-800D01*
G02Y525525I-900J1202D01*
G03X291669I600J800D01*
G02Y523121I900J-1202D01*
G37*
G36*
G01X307066Y522945D02*
G03X305866I-600J-800D01*
G02Y525349I-900J1202D01*
G03X307066I600J800D01*
G02Y522945I900J-1202D01*
G37*
G36*
G01X299637Y522835D02*
G03X298437I-600J-800D01*
G02Y525239I-900J1202D01*
G03X299637I600J800D01*
G02Y522835I900J-1202D01*
G37*
G36*
G01X315891Y515502D02*
G03X314691I-600J-800D01*
G02Y517906I-900J1202D01*
G03X315891I600J800D01*
G02Y515502I900J-1202D01*
G37*
G36*
G01X324239Y515430D02*
G03X323039I-600J-800D01*
G02Y517834I-900J1202D01*
G03X324239I600J800D01*
G02Y515430I900J-1202D01*
G37*
G36*
G01X291669Y515393D02*
G03X290469I-600J-800D01*
G02Y517797I-900J1202D01*
G03X291669I600J800D01*
G02Y515393I900J-1202D01*
G37*
G36*
G01X307066Y515217D02*
G03X305866I-600J-800D01*
G02Y517621I-900J1202D01*
G03X307066I600J800D01*
G02Y515217I900J-1202D01*
G37*
G36*
G01X299637Y515107D02*
G03X298437I-600J-800D01*
G02Y517511I-900J1202D01*
G03X299637I600J800D01*
G02Y515107I900J-1202D01*
G37*
G36*
G01X249916Y420141D02*
G03Y418941I800J-600D01*
G02X247512I-1202J-900D01*
G03Y420141I-800J600D01*
G02X249916I1202J900D01*
G37*
G36*
G01X240948Y419998D02*
G03Y418798I800J-600D01*
G02X238544I-1202J-900D01*
G03Y419998I-800J600D01*
G02X240948I1202J900D01*
G37*
G36*
G01X275733Y419894D02*
G03Y418694I800J-600D01*
G02X273329I-1202J-900D01*
G03Y419894I-800J600D01*
G02X275733I1202J900D01*
G37*
G36*
G01X267242Y419751D02*
G03Y418551I800J-600D01*
G02X264838I-1202J-900D01*
G03Y419751I-800J600D01*
G02X267242I1202J900D01*
G37*
G36*
G01X258774Y419750D02*
G03Y418550I800J-600D01*
G02X256370I-1202J-900D01*
G03Y419750I-800J600D01*
G02X258774I1202J900D01*
G37*
G36*
G01X249916Y409636D02*
G03Y408436I800J-600D01*
G02X247512I-1202J-900D01*
G03Y409636I-800J600D01*
G02X249916I1202J900D01*
G37*
G36*
G01X240948Y409493D02*
G03Y408293I800J-600D01*
G02X238544I-1202J-900D01*
G03Y409493I-800J600D01*
G02X240948I1202J900D01*
G37*
G36*
G01X275733Y409389D02*
G03Y408189I800J-600D01*
G02X273329I-1202J-900D01*
G03Y409389I-800J600D01*
G02X275733I1202J900D01*
G37*
G36*
G01X267242Y409246D02*
G03Y408046I800J-600D01*
G02X264838I-1202J-900D01*
G03Y409246I-800J600D01*
G02X267242I1202J900D01*
G37*
G36*
G01X258774Y409245D02*
G03Y408045I800J-600D01*
G02X256370I-1202J-900D01*
G03Y409245I-800J600D01*
G02X258774I1202J900D01*
G37*
G36*
G01X249916Y399121D02*
G03Y397921I800J-600D01*
G02X247512I-1202J-900D01*
G03Y399121I-800J600D01*
G02X249916I1202J900D01*
G37*
G36*
G01X240948Y398978D02*
G03Y397778I800J-600D01*
G02X238544I-1202J-900D01*
G03Y398978I-800J600D01*
G02X240948I1202J900D01*
G37*
G36*
G01X275733Y398874D02*
G03Y397674I800J-600D01*
G02X273329I-1202J-900D01*
G03Y398874I-800J600D01*
G02X275733I1202J900D01*
G37*
G36*
G01X267242Y398731D02*
G03Y397531I800J-600D01*
G02X264838I-1202J-900D01*
G03Y398731I-800J600D01*
G02X267242I1202J900D01*
G37*
G36*
G01X258774Y398730D02*
G03Y397530I800J-600D01*
G02X256370I-1202J-900D01*
G03Y398730I-800J600D01*
G02X258774I1202J900D01*
G37*
G36*
G01X169982Y377727D02*
G02X170002Y377205I-6597J-514D01*
G02X156766I-6618J0D01*
G02X169982Y377727I6618J0D01*
G37*
G36*
G01X342826Y347453D02*
G03X341626I-600J-800D01*
G02Y349857I-900J1202D01*
G03X342826I600J800D01*
G02Y347453I900J-1202D01*
G37*
G36*
G01X331785D02*
G03X330585I-600J-800D01*
G02Y349857I-900J1202D01*
G03X331785I600J800D01*
G02Y347453I900J-1202D01*
G37*
G36*
G01X342916Y341259D02*
G03X341716I-600J-800D01*
G02Y343663I-900J1202D01*
G03X342916I600J800D01*
G02Y341259I900J-1202D01*
G37*
G36*
G01X331875D02*
G03X330675I-600J-800D01*
G02Y343663I-900J1202D01*
G03X331875I600J800D01*
G02Y341259I900J-1202D01*
G37*
G36*
G01X342916Y334070D02*
G03X341716I-600J-800D01*
G02Y336474I-900J1202D01*
G03X342916I600J800D01*
G02Y334070I900J-1202D01*
G37*
G36*
G01X331875D02*
G03X330675I-600J-800D01*
G02Y336474I-900J1202D01*
G03X331875I600J800D01*
G02Y334070I900J-1202D01*
G37*
G36*
G01X342916Y324733D02*
G03X341716I-600J-800D01*
G02Y327137I-900J1202D01*
G03X342916I600J800D01*
G02Y324733I900J-1202D01*
G37*
G36*
G01X331875D02*
G03X330675I-600J-800D01*
G02Y327137I-900J1202D01*
G03X331875I600J800D01*
G02Y324733I900J-1202D01*
G37*
G36*
G01X342916Y317432D02*
G03X341716I-600J-800D01*
G02Y319836I-900J1202D01*
G03X342916I600J800D01*
G02Y317432I900J-1202D01*
G37*
G36*
G01X331875D02*
G03X330675I-600J-800D01*
G02Y319836I-900J1202D01*
G03X331875I600J800D01*
G02Y317432I900J-1202D01*
G37*
G36*
G01X342834Y310778D02*
G03X341634I-600J-800D01*
G02Y313182I-900J1202D01*
G03X342834I600J800D01*
G02Y310778I900J-1202D01*
G37*
G36*
G01X331793D02*
G03X330593I-600J-800D01*
G02Y313182I-900J1202D01*
G03X331793I600J800D01*
G02Y310778I900J-1202D01*
G37*
G36*
G01X116668Y397872D02*
G02X116602Y394460I3252J-1770D01*
G03X115223Y394892I-896J-444D01*
G02X115274Y397493I-725J1315D01*
G03X116668Y397872I516J857D01*
G37*
G36*
G01X109016Y419566D02*
Y425519D01*
X116832Y433336D01*
G03X116888Y433977I-353J354D01*
G02X123299Y434589I3032J2125D01*
G03X124211Y433180I913J-409D01*
G01X135629D01*
G03X136541Y434589I-1J1000D01*
G02X143299I3379J1513D01*
G03X144211Y433180I913J-409D01*
G01X148968D01*
X151336Y430812D01*
X156037D01*
G03X156960Y432198I0J1000D01*
G02X158807Y434970I1847J771D01*
G01X159019D01*
G03X160018Y436030I0J1000D01*
G02X163016I1499J89D01*
G03X164015Y434970I999J-60D01*
G01X218956D01*
X256302Y472316D01*
X261543D01*
X264322Y475095D01*
G02X267152Y472265I1415J-1415D01*
G01X263625Y468738D01*
G03X263624Y468030I353J-354D01*
G01X267137Y464517D01*
G02X264307Y461687I-1415J-1415D01*
G01X261746Y464248D01*
X259775D01*
X222337Y426810D01*
X149678D01*
X147310Y429178D01*
X144139D01*
G03X143242Y427736I0J-1000D01*
G02X136598I-3322J-1634D01*
G03X135701Y429178I-897J442D01*
G01X124139D01*
G03X123242Y427736I0J-1000D01*
G02X116357Y425095I-3323J-1633D01*
G03X114688Y425531I-962J-272D01*
G01X113018Y423861D01*
Y419566D01*
G02X109016I-2001J0D01*
G37*
G36*
G01X123238Y765777D02*
G02X116602I-3318J-1643D01*
G03X115706Y767220I-896J443D01*
G01X112836D01*
G02Y771024I0J1902D01*
G01X115718D01*
G03X116612Y772472I0J1000D01*
G02X123228I3308J1662D01*
G03X124122Y771024I894J-448D01*
G01X126837D01*
X136982Y781168D01*
G03X137021Y781832I-353J354D01*
G01X137020Y781833D01*
G02X143204Y782424I2900J2301D01*
G03X144091Y780962I887J-462D01*
G01X150271D01*
X151721Y779512D01*
X156093D01*
G03X157080Y780674I0J1000D01*
G02X158956Y782884I1876J309D01*
G01X158990D01*
G03X159985Y783986I0J1000D01*
G02X160026Y784523I1494J156D01*
G03X159057Y785778I-967J255D01*
G02X160506Y786898I-4J1502D01*
G03X161475Y785643I967J-255D01*
G02X162973Y783986I4J-1502D01*
G03X163968Y782884I995J-102D01*
G01X174278D01*
X191440Y800046D01*
X213919D01*
X236447Y822574D01*
X252095D01*
X254492Y824971D01*
G02X257182Y822281I1345J-1345D01*
G01X253671Y818770D01*
X238023D01*
X237043Y817791D01*
G03X237397Y816938I354J-353D01*
G01X253631D01*
X257032Y813537D01*
G02X254342Y810847I-1345J-1345D01*
G01X252055Y813134D01*
X237155D01*
X216540Y792520D01*
X194897D01*
X178087Y775710D01*
X150145D01*
X148695Y777160D01*
X144163D01*
G03X143261Y775729I1J-1000D01*
G02X136369Y773087I-3341J-1594D01*
G03X134703Y773511I-959J-283D01*
G01X128413Y767220D01*
X124134D01*
G03X123238Y765777I0J-1000D01*
G37*
G36*
G01X169982Y1952727D02*
G02X170003Y1952205I-6597J-527D01*
G02X156766I-6618J0D01*
G02X169982Y1952727I6618J0D01*
G37*
G36*
G01X316910Y1923081D02*
G03X315710I-600J-800D01*
G02Y1925485I-900J1202D01*
G03X316910I600J800D01*
G02Y1923081I900J-1202D01*
G37*
G36*
G01X294854Y1922901D02*
G03X293654I-600J-800D01*
G02Y1925305I-900J1202D01*
G03X294854I600J800D01*
G02Y1922901I900J-1202D01*
G37*
G36*
G01X316910Y1916126D02*
G03X315710I-600J-800D01*
G02Y1918530I-900J1202D01*
G03X316910I600J800D01*
G02Y1916126I900J-1202D01*
G37*
G36*
G01X294854Y1915946D02*
G03X293654I-600J-800D01*
G02Y1918350I-900J1202D01*
G03X294854I600J800D01*
G02Y1915946I900J-1202D01*
G37*
G36*
G01X316910Y1909210D02*
G03X315710I-600J-800D01*
G02Y1911614I-900J1202D01*
G03X316910I600J800D01*
G02Y1909210I900J-1202D01*
G37*
G36*
G01X294854Y1909030D02*
G03X293654I-600J-800D01*
G02Y1911434I-900J1202D01*
G03X294854I600J800D01*
G02Y1909030I900J-1202D01*
G37*
G36*
G01X294833Y1881121D02*
X294834Y1885021D01*
G02X299158Y1894363I12254J0D01*
G02X315014I7928J-9324D01*
G02X319338Y1885021I-7930J-9342D01*
G01Y1881121D01*
G02X315169Y1871913I-12253J0D01*
G02X299006Y1871910I-8083J9189D01*
G02X294833Y1881121I8080J9211D01*
G37*
G36*
G01X269137Y1838891D02*
G03X267937I-600J-800D01*
G02Y1841295I-900J1202D01*
G03X269137I600J800D01*
G02Y1838891I900J-1202D01*
G37*
G36*
G01X260559Y1838888D02*
G03X259359I-600J-800D01*
G02Y1841292I-900J1202D01*
G03X260559I600J800D01*
G02Y1838888I900J-1202D01*
G37*
G36*
G01X252388D02*
G03X251188I-600J-800D01*
G02Y1841292I-900J1202D01*
G03X252388I600J800D01*
G02Y1838888I900J-1202D01*
G37*
G36*
G01X269137Y1831936D02*
G03X267937I-600J-800D01*
G02Y1834340I-900J1202D01*
G03X269137I600J800D01*
G02Y1831936I900J-1202D01*
G37*
G36*
G01X260559Y1831933D02*
G03X259359I-600J-800D01*
G02Y1834337I-900J1202D01*
G03X260559I600J800D01*
G02Y1831933I900J-1202D01*
G37*
G36*
G01X252388D02*
G03X251188I-600J-800D01*
G02Y1834337I-900J1202D01*
G03X252388I600J800D01*
G02Y1831933I900J-1202D01*
G37*
G36*
G01X269137Y1825020D02*
G03X267937I-600J-800D01*
G02Y1827424I-900J1202D01*
G03X269137I600J800D01*
G02Y1825020I900J-1202D01*
G37*
G36*
G01X260559Y1825017D02*
G03X259359I-600J-800D01*
G02Y1827421I-900J1202D01*
G03X260559I600J800D01*
G02Y1825017I900J-1202D01*
G37*
G36*
G01X252388D02*
G03X251188I-600J-800D01*
G02Y1827421I-900J1202D01*
G03X252388I600J800D01*
G02Y1825017I900J-1202D01*
G37*
G36*
G01X269496Y1817875D02*
G03X268296I-600J-800D01*
G02Y1820279I-900J1202D01*
G03X269496I600J800D01*
G02Y1817875I900J-1202D01*
G37*
G36*
G01X260739Y1817872D02*
G03X259539I-600J-800D01*
G02Y1820276I-900J1202D01*
G03X260739I600J800D01*
G02Y1817872I900J-1202D01*
G37*
G36*
G01X252568D02*
G03X251368I-600J-800D01*
G02Y1820276I-900J1202D01*
G03X252568I600J800D01*
G02Y1817872I900J-1202D01*
G37*
G36*
G01X269496Y1810920D02*
G03X268296I-600J-800D01*
G02Y1813324I-900J1202D01*
G03X269496I600J800D01*
G02Y1810920I900J-1202D01*
G37*
G36*
G01X260739Y1810917D02*
G03X259539I-600J-800D01*
G02Y1813321I-900J1202D01*
G03X260739I600J800D01*
G02Y1810917I900J-1202D01*
G37*
G36*
G01X252568D02*
G03X251368I-600J-800D01*
G02Y1813321I-900J1202D01*
G03X252568I600J800D01*
G02Y1810917I900J-1202D01*
G37*
G36*
G01X269496Y1804004D02*
G03X268296I-600J-800D01*
G02Y1806408I-900J1202D01*
G03X269496I600J800D01*
G02Y1804004I900J-1202D01*
G37*
G36*
G01X260739Y1804001D02*
G03X259539I-600J-800D01*
G02Y1806405I-900J1202D01*
G03X260739I600J800D01*
G02Y1804001I900J-1202D01*
G37*
G36*
G01X252568D02*
G03X251368I-600J-800D01*
G02Y1806405I-900J1202D01*
G03X252568I600J800D01*
G02Y1804001I900J-1202D01*
G37*
G36*
G01X106044Y1792524D02*
G03X106113Y1793671I-782J623D01*
G02X108567Y1793525I1278J789D01*
G03X108498Y1792378I782J-623D01*
G02X106044Y1792524I-1278J-789D01*
G37*
G36*
G01X169982Y1777727D02*
G02X170003Y1777205I-6597J-527D01*
G02X156766I-6618J0D01*
G02X169982Y1777727I6618J0D01*
G37*
G36*
G01X264598Y1720938D02*
G03X263398I-600J-800D01*
G02Y1723342I-900J1202D01*
G03X264598I600J800D01*
G02Y1720938I900J-1202D01*
G37*
G36*
G01X253557D02*
G03X252357I-600J-800D01*
G02Y1723342I-900J1202D01*
G03X253557I600J800D01*
G02Y1720938I900J-1202D01*
G37*
G36*
G01X264859Y1713476D02*
G03X263659I-600J-800D01*
G02Y1715880I-900J1202D01*
G03X264859I600J800D01*
G02Y1713476I900J-1202D01*
G37*
G36*
G01X253818D02*
G03X252618I-600J-800D01*
G02Y1715880I-900J1202D01*
G03X253818I600J800D01*
G02Y1713476I900J-1202D01*
G37*
G36*
G01X264859Y1705748D02*
G03X263659I-600J-800D01*
G02Y1708152I-900J1202D01*
G03X264859I600J800D01*
G02Y1705748I900J-1202D01*
G37*
G36*
G01X253818D02*
G03X252618I-600J-800D01*
G02Y1708152I-900J1202D01*
G03X253818I600J800D01*
G02Y1705748I900J-1202D01*
G37*
G36*
G01X160592Y1702570D02*
G03X159392I-600J-800D01*
G02Y1704974I-900J1202D01*
G03X160592I600J800D01*
G02Y1702570I900J-1202D01*
G37*
G36*
G01X264859Y1696411D02*
G03X263659I-600J-800D01*
G02Y1698815I-900J1202D01*
G03X264859I600J800D01*
G02Y1696411I900J-1202D01*
G37*
G36*
G01X253818D02*
G03X252618I-600J-800D01*
G02Y1698815I-900J1202D01*
G03X253818I600J800D01*
G02Y1696411I900J-1202D01*
G37*
G36*
G01X160592Y1694131D02*
G03X159392I-600J-800D01*
G02Y1696535I-900J1202D01*
G03X160592I600J800D01*
G02Y1694131I900J-1202D01*
G37*
G36*
G01Y1686403D02*
G03X159392I-600J-800D01*
G02Y1688807I-900J1202D01*
G03X160592I600J800D01*
G02Y1686403I900J-1202D01*
G37*
G36*
G01X264859Y1685906D02*
G03X263659I-600J-800D01*
G02Y1688310I-900J1202D01*
G03X264859I600J800D01*
G02Y1685906I900J-1202D01*
G37*
G36*
G01X253818D02*
G03X252618I-600J-800D01*
G02Y1688310I-900J1202D01*
G03X253818I600J800D01*
G02Y1685906I900J-1202D01*
G37*
G36*
G01X160592Y1677066D02*
G03X159392I-600J-800D01*
G02Y1679470I-900J1202D01*
G03X160592I600J800D01*
G02Y1677066I900J-1202D01*
G37*
G36*
G01X264859Y1675391D02*
G03X263659I-600J-800D01*
G02Y1677795I-900J1202D01*
G03X264859I600J800D01*
G02Y1675391I900J-1202D01*
G37*
G36*
G01X253818D02*
G03X252618I-600J-800D01*
G02Y1677795I-900J1202D01*
G03X253818I600J800D01*
G02Y1675391I900J-1202D01*
G37*
G36*
G01X272442Y1667145D02*
G03X271242I-600J-800D01*
G02Y1669549I-900J1202D01*
G03X272442I600J800D01*
G02Y1667145I900J-1202D01*
G37*
G36*
G01X260664D02*
G03X259464I-600J-800D01*
G02Y1669549I-900J1202D01*
G03X260664I600J800D01*
G02Y1667145I900J-1202D01*
G37*
G36*
G01X160592Y1666561D02*
G03X159392I-600J-800D01*
G02Y1668965I-900J1202D01*
G03X160592I600J800D01*
G02Y1666561I900J-1202D01*
G37*
G36*
G01X272442Y1658706D02*
G03X271242I-600J-800D01*
G02Y1661110I-900J1202D01*
G03X272442I600J800D01*
G02Y1658706I900J-1202D01*
G37*
G36*
G01X260664D02*
G03X259464I-600J-800D01*
G02Y1661110I-900J1202D01*
G03X260664I600J800D01*
G02Y1658706I900J-1202D01*
G37*
G36*
G01X160592Y1656046D02*
G03X159392I-600J-800D01*
G02Y1658450I-900J1202D01*
G03X160592I600J800D01*
G02Y1656046I900J-1202D01*
G37*
G36*
G01X272442Y1650978D02*
G03X271242I-600J-800D01*
G02Y1653382I-900J1202D01*
G03X272442I600J800D01*
G02Y1650978I900J-1202D01*
G37*
G36*
G01X260664D02*
G03X259464I-600J-800D01*
G02Y1653382I-900J1202D01*
G03X260664I600J800D01*
G02Y1650978I900J-1202D01*
G37*
G36*
G01X272442Y1641641D02*
G03X271242I-600J-800D01*
G02Y1644045I-900J1202D01*
G03X272442I600J800D01*
G02Y1641641I900J-1202D01*
G37*
G36*
G01X260664D02*
G03X259464I-600J-800D01*
G02Y1644045I-900J1202D01*
G03X260664I600J800D01*
G02Y1641641I900J-1202D01*
G37*
G36*
G01X272442Y1631136D02*
G03X271242I-600J-800D01*
G02Y1633540I-900J1202D01*
G03X272442I600J800D01*
G02Y1631136I900J-1202D01*
G37*
G36*
G01X260664D02*
G03X259464I-600J-800D01*
G02Y1633540I-900J1202D01*
G03X260664I600J800D01*
G02Y1631136I900J-1202D01*
G37*
G36*
G01X272442Y1620621D02*
G03X271242I-600J-800D01*
G02Y1623025I-900J1202D01*
G03X272442I600J800D01*
G02Y1620621I900J-1202D01*
G37*
G36*
G01X260664D02*
G03X259464I-600J-800D01*
G02Y1623025I-900J1202D01*
G03X260664I600J800D01*
G02Y1620621I900J-1202D01*
G37*
G36*
G01X169982Y1602727D02*
G02X170003Y1602205I-6597J-527D01*
G02X156766I-6618J0D01*
G02X169982Y1602727I6618J0D01*
G37*
G36*
G01X285095Y1546988D02*
G03X283895I-600J-800D01*
G02Y1549392I-900J1202D01*
G03X285095I600J800D01*
G02Y1546988I900J-1202D01*
G37*
G36*
G01X263039Y1546808D02*
G03X261839I-600J-800D01*
G02Y1549212I-900J1202D01*
G03X263039I600J800D01*
G02Y1546808I900J-1202D01*
G37*
G36*
G01X285095Y1540033D02*
G03X283895I-600J-800D01*
G02Y1542437I-900J1202D01*
G03X285095I600J800D01*
G02Y1540033I900J-1202D01*
G37*
G36*
G01X263039Y1539853D02*
G03X261839I-600J-800D01*
G02Y1542257I-900J1202D01*
G03X263039I600J800D01*
G02Y1539853I900J-1202D01*
G37*
G36*
G01X285095Y1533117D02*
G03X283895I-600J-800D01*
G02Y1535521I-900J1202D01*
G03X285095I600J800D01*
G02Y1533117I900J-1202D01*
G37*
G36*
G01X263039Y1532937D02*
G03X261839I-600J-800D01*
G02Y1535341I-900J1202D01*
G03X263039I600J800D01*
G02Y1532937I900J-1202D01*
G37*
G36*
G01X311564Y1492771D02*
G03X310364I-600J-800D01*
G02Y1495175I-900J1202D01*
G03X311564I600J800D01*
G02Y1492771I900J-1202D01*
G37*
G36*
G01X302986Y1492768D02*
G03X301786I-600J-800D01*
G02Y1495172I-900J1202D01*
G03X302986I600J800D01*
G02Y1492768I900J-1202D01*
G37*
G36*
G01X294815D02*
G03X293615I-600J-800D01*
G02Y1495172I-900J1202D01*
G03X294815I600J800D01*
G02Y1492768I900J-1202D01*
G37*
G36*
G01X311564Y1485816D02*
G03X310364I-600J-800D01*
G02Y1488220I-900J1202D01*
G03X311564I600J800D01*
G02Y1485816I900J-1202D01*
G37*
G36*
G01X302986Y1485813D02*
G03X301786I-600J-800D01*
G02Y1488217I-900J1202D01*
G03X302986I600J800D01*
G02Y1485813I900J-1202D01*
G37*
G36*
G01X294815D02*
G03X293615I-600J-800D01*
G02Y1488217I-900J1202D01*
G03X294815I600J800D01*
G02Y1485813I900J-1202D01*
G37*
G36*
G01X311564Y1478900D02*
G03X310364I-600J-800D01*
G02Y1481304I-900J1202D01*
G03X311564I600J800D01*
G02Y1478900I900J-1202D01*
G37*
G36*
G01X302986Y1478897D02*
G03X301786I-600J-800D01*
G02Y1481301I-900J1202D01*
G03X302986I600J800D01*
G02Y1478897I900J-1202D01*
G37*
G36*
G01X294815D02*
G03X293615I-600J-800D01*
G02Y1481301I-900J1202D01*
G03X294815I600J800D01*
G02Y1478897I900J-1202D01*
G37*
G36*
G01X311923Y1471755D02*
G03X310723I-600J-800D01*
G02Y1474159I-900J1202D01*
G03X311923I600J800D01*
G02Y1471755I900J-1202D01*
G37*
G36*
G01X303166Y1471752D02*
G03X301966I-600J-800D01*
G02Y1474156I-900J1202D01*
G03X303166I600J800D01*
G02Y1471752I900J-1202D01*
G37*
G36*
G01X294995D02*
G03X293795I-600J-800D01*
G02Y1474156I-900J1202D01*
G03X294995I600J800D01*
G02Y1471752I900J-1202D01*
G37*
G36*
G01X311923Y1464800D02*
G03X310723I-600J-800D01*
G02Y1467204I-900J1202D01*
G03X311923I600J800D01*
G02Y1464800I900J-1202D01*
G37*
G36*
G01X303166Y1464797D02*
G03X301966I-600J-800D01*
G02Y1467201I-900J1202D01*
G03X303166I600J800D01*
G02Y1464797I900J-1202D01*
G37*
G36*
G01X294995D02*
G03X293795I-600J-800D01*
G02Y1467201I-900J1202D01*
G03X294995I600J800D01*
G02Y1464797I900J-1202D01*
G37*
G36*
G01X311923Y1457884D02*
G03X310723I-600J-800D01*
G02Y1460288I-900J1202D01*
G03X311923I600J800D01*
G02Y1457884I900J-1202D01*
G37*
G36*
G01X303166Y1457881D02*
G03X301966I-600J-800D01*
G02Y1460285I-900J1202D01*
G03X303166I600J800D01*
G02Y1457881I900J-1202D01*
G37*
G36*
G01X294995D02*
G03X293795I-600J-800D01*
G02Y1460285I-900J1202D01*
G03X294995I600J800D01*
G02Y1457881I900J-1202D01*
G37*
G36*
G01X124008Y1466874D02*
X125158D01*
X135483Y1477198D01*
X135664D01*
G03X136569Y1478624I0J1000D01*
G02X143271I3351J1573D01*
G03X144176Y1477198I905J-426D01*
G01X151467D01*
X152832Y1475834D01*
X156329D01*
G03X157324Y1476934I0J1000D01*
G02X159216Y1479026I1892J190D01*
G01X163488D01*
X181015Y1496552D01*
X220124D01*
G03X220477Y1496698I0J500D01*
G01X246492Y1522714D01*
X297890D01*
X300922Y1525746D01*
G02X303612Y1523056I1345J-1345D01*
G01X299785Y1519230D01*
G03Y1518522I353J-354D01*
G01X303079Y1515228D01*
G02X300389Y1512538I-1345J-1345D01*
G01X297354Y1515573D01*
G03X297001Y1515720I-354J-353D01*
G01X249598D01*
G03X249245Y1515574I0J-500D01*
G01X222754Y1489082D01*
X184051D01*
X166999Y1472030D01*
X151256D01*
X150037Y1473249D01*
G03X149684Y1473396I-354J-353D01*
G01X144076D01*
G03X143192Y1471928I0J-1000D01*
G02X136218Y1470153I-3272J-1731D01*
G03X134511Y1470848I-1000J-12D01*
G01X126734Y1463070D01*
X124233D01*
G03X123315Y1461672I-1J-1000D01*
G02X116525I-3395J-1475D01*
G03X115607Y1463070I-917J398D01*
G01X114308D01*
X109103Y1461563D01*
G02X108045Y1465215I-529J1826D01*
G01X113768Y1466874D01*
X115832D01*
G03X116702Y1468368I1J1000D01*
G02X123138I3218J1829D01*
G03X124008Y1466874I869J-494D01*
G37*
G36*
G01X169982Y1427727D02*
G02X170003Y1427205I-6597J-527D01*
G02X156766I-6618J0D01*
G02X169982Y1427727I6618J0D01*
G37*
G36*
G01X26122Y1345527D02*
G02X14107Y1342598I-5650J-2929D01*
G02X14821Y1345528I6365J1D01*
G03X14395Y1346875I-888J460D01*
G02X18000Y1349605I1156J2219D01*
G03X19182Y1348831I979J205D01*
G02X21762Y1348830I1288J-6233D01*
G03X22944Y1349605I203J979D01*
G02X26548Y1346875I2449J-511D01*
G03X26122Y1345527I462J-887D01*
G37*
G36*
G01X65355Y1494272D02*
G02X44668Y1514960I0J20687D01*
G02X86042I20687J0D01*
G02X65355Y1494272I-20687J-1D01*
G37*
G36*
G01X269434Y1532937D02*
G02Y1535341I-900J1202D01*
G03X270634I600J800D01*
G02X272650Y1535144I900J-1202D01*
G03X274195Y1535216I743J669D01*
G02X276300Y1535521I1205J-897D01*
G03X277500I600J800D01*
G02Y1533117I900J-1202D01*
G03X276300I-600J-800D01*
G02X274284Y1533314I-900J1202D01*
G03X272739Y1533242I-743J-669D01*
G02X270634Y1532937I-1205J897D01*
G03X269434I-600J-800D01*
G37*
G36*
G01Y1539853D02*
G02Y1542257I-900J1202D01*
G03X270634I600J800D01*
G02X272650Y1542060I900J-1202D01*
G03X274195Y1542132I743J669D01*
G02X276300Y1542437I1205J-897D01*
G03X277500I600J800D01*
G02Y1540033I900J-1202D01*
G03X276300I-600J-800D01*
G02X274284Y1540230I-900J1202D01*
G03X272739Y1540158I-743J-669D01*
G02X270634Y1539853I-1205J897D01*
G03X269434I-600J-800D01*
G37*
G36*
G01Y1546808D02*
G02Y1549212I-900J1202D01*
G03X270634I600J800D01*
G02X272650Y1549015I900J-1202D01*
G03X274195Y1549087I743J669D01*
G02X276300Y1549392I1205J-897D01*
G03X277500I600J800D01*
G02Y1546988I900J-1202D01*
G03X276300I-600J-800D01*
G02X274284Y1547185I-900J1202D01*
G03X272739Y1547113I-743J-669D01*
G02X270634Y1546808I-1205J897D01*
G03X269434I-600J-800D01*
G37*
G36*
G01X123238Y1809871D02*
G02X116602I-3318J-1643D01*
G03X115706Y1811314I-896J443D01*
G01X113105D01*
X112007Y1810216D01*
X108819D01*
G02Y1814020I0J1902D01*
G01X110431D01*
X111529Y1815118D01*
X115718D01*
G03X116612Y1816566I0J1000D01*
G02X123228I3308J1662D01*
G03X124122Y1815118I894J-448D01*
G01X135718D01*
G03X136612Y1816566I0J1000D01*
G02X143228I3308J1662D01*
G03X144122Y1815118I894J-448D01*
G01X166283D01*
X172644Y1821478D01*
G03X171937Y1823186I-707J708D01*
G01X159075D01*
G02Y1826988I0J1901D01*
G01X159353D01*
G03X160349Y1828083I0J1000D01*
G02X160399Y1828635I1495J143D01*
G03X159591Y1829896I-962J273D01*
G02X161267Y1830970I231J1484D01*
G03X162075Y1829709I962J-273D01*
G02X163339Y1828083I-231J-1484D01*
G03X164335Y1826988I996J-95D01*
G01X171395D01*
X184923Y1840516D01*
X230711D01*
G03X231064Y1840662I0J500D01*
G01X255585Y1865184D01*
X277905D01*
X278631Y1865910D01*
G02X281321Y1863220I1345J-1345D01*
G01X280203Y1862102D01*
G03Y1861394I353J-354D01*
G01X281585Y1860013D01*
G02X278895Y1857323I-1345J-1345D01*
G01X278252Y1857966D01*
X258576D01*
X233909Y1833300D01*
X190051D01*
G03X189698Y1833154I0J-500D01*
G01X167859Y1811314D01*
X144134D01*
G03X143238Y1809871I0J-1000D01*
G02X136602I-3318J-1643D01*
G03X135706Y1811314I-896J443D01*
G01X124134D01*
G03X123238Y1809871I0J-1000D01*
G37*
G36*
G01X65355Y1844272D02*
G02X44668Y1864960I0J20687D01*
G02X86042I20687J0D01*
G02X65355Y1844272I-20687J-1D01*
G37*
G36*
G01X301249Y1909030D02*
G02Y1911434I-900J1202D01*
G03X302449I600J800D01*
G02X304465Y1911237I900J-1202D01*
G03X306010Y1911309I743J669D01*
G02X308115Y1911614I1205J-897D01*
G03X309315I600J800D01*
G02Y1909210I900J-1202D01*
G03X308115I-600J-800D01*
G02X306099Y1909407I-900J1202D01*
G03X304554Y1909335I-743J-669D01*
G02X302449Y1909030I-1205J897D01*
G03X301249I-600J-800D01*
G37*
G36*
G01Y1915946D02*
G02Y1918350I-900J1202D01*
G03X302449I600J800D01*
G02X304465Y1918153I900J-1202D01*
G03X306010Y1918225I743J669D01*
G02X308115Y1918530I1205J-897D01*
G03X309315I600J800D01*
G02Y1916126I900J-1202D01*
G03X308115I-600J-800D01*
G02X306099Y1916323I-900J1202D01*
G03X304554Y1916251I-743J-669D01*
G02X302449Y1915946I-1205J897D01*
G03X301249I-600J-800D01*
G37*
G36*
G01Y1922901D02*
G02Y1925305I-900J1202D01*
G03X302449I600J800D01*
G02X304465Y1925108I900J-1202D01*
G03X306010Y1925180I743J669D01*
G02X308115Y1925485I1205J-897D01*
G03X309315I600J800D01*
G02Y1923081I900J-1202D01*
G03X308115I-600J-800D01*
G02X306099Y1923278I-900J1202D01*
G03X304554Y1923206I-743J-669D01*
G02X302449Y1922901I-1205J897D01*
G03X301249I-600J-800D01*
G37*
G36*
G01X157849Y1353055D02*
G03X156649I-600J-800D01*
G02Y1355459I-900J1202D01*
G03X157849I600J800D01*
G02Y1353055I900J-1202D01*
G37*
G36*
G01Y1344616D02*
G03X156649I-600J-800D01*
G02Y1347020I-900J1202D01*
G03X157849I600J800D01*
G02Y1344616I900J-1202D01*
G37*
G36*
G01X245025Y1338638D02*
G03X243825I-600J-800D01*
G02Y1341042I-900J1202D01*
G03X245025I600J800D01*
G02Y1338638I900J-1202D01*
G37*
G36*
G01X237529D02*
G03X236329I-600J-800D01*
G02Y1341042I-900J1202D01*
G03X237529I600J800D01*
G02Y1338638I900J-1202D01*
G37*
G36*
G01X228706D02*
G03X227506I-600J-800D01*
G02Y1341042I-900J1202D01*
G03X228706I600J800D01*
G02Y1338638I900J-1202D01*
G37*
G36*
G01X221278D02*
G03X220078I-600J-800D01*
G02Y1341042I-900J1202D01*
G03X221278I600J800D01*
G02Y1338638I900J-1202D01*
G37*
G36*
G01X157849Y1336888D02*
G03X156649I-600J-800D01*
G02Y1339292I-900J1202D01*
G03X157849I600J800D01*
G02Y1336888I900J-1202D01*
G37*
G36*
G01X245025Y1331119D02*
G03X243825I-600J-800D01*
G02Y1333523I-900J1202D01*
G03X245025I600J800D01*
G02Y1331119I900J-1202D01*
G37*
G36*
G01X237529D02*
G03X236329I-600J-800D01*
G02Y1333523I-900J1202D01*
G03X237529I600J800D01*
G02Y1331119I900J-1202D01*
G37*
G36*
G01X228706D02*
G03X227506I-600J-800D01*
G02Y1333523I-900J1202D01*
G03X228706I600J800D01*
G02Y1331119I900J-1202D01*
G37*
G36*
G01X221278D02*
G03X220078I-600J-800D01*
G02Y1333523I-900J1202D01*
G03X221278I600J800D01*
G02Y1331119I900J-1202D01*
G37*
G36*
G01X157849Y1327551D02*
G03X156649I-600J-800D01*
G02Y1329955I-900J1202D01*
G03X157849I600J800D01*
G02Y1327551I900J-1202D01*
G37*
G36*
G01X245025Y1323083D02*
G03X243825I-600J-800D01*
G02Y1325487I-900J1202D01*
G03X245025I600J800D01*
G02Y1323083I900J-1202D01*
G37*
G36*
G01X237529D02*
G03X236329I-600J-800D01*
G02Y1325487I-900J1202D01*
G03X237529I600J800D01*
G02Y1323083I900J-1202D01*
G37*
G36*
G01X228706D02*
G03X227506I-600J-800D01*
G02Y1325487I-900J1202D01*
G03X228706I600J800D01*
G02Y1323083I900J-1202D01*
G37*
G36*
G01X221278D02*
G03X220078I-600J-800D01*
G02Y1325487I-900J1202D01*
G03X221278I600J800D01*
G02Y1323083I900J-1202D01*
G37*
G36*
G01X269722Y1317752D02*
G03X268522I-600J-800D01*
G02Y1320156I-900J1202D01*
G03X269722I600J800D01*
G02Y1317752I900J-1202D01*
G37*
G36*
G01X258681D02*
G03X257481I-600J-800D01*
G02Y1320156I-900J1202D01*
G03X258681I600J800D01*
G02Y1317752I900J-1202D01*
G37*
G36*
G01X157849Y1317046D02*
G03X156649I-600J-800D01*
G02Y1319450I-900J1202D01*
G03X157849I600J800D01*
G02Y1317046I900J-1202D01*
G37*
G36*
G01X245025Y1315640D02*
G03X243825I-600J-800D01*
G02Y1318044I-900J1202D01*
G03X245025I600J800D01*
G02Y1315640I900J-1202D01*
G37*
G36*
G01X237529D02*
G03X236329I-600J-800D01*
G02Y1318044I-900J1202D01*
G03X237529I600J800D01*
G02Y1315640I900J-1202D01*
G37*
G36*
G01X228706D02*
G03X227506I-600J-800D01*
G02Y1318044I-900J1202D01*
G03X228706I600J800D01*
G02Y1315640I900J-1202D01*
G37*
G36*
G01X221278D02*
G03X220078I-600J-800D01*
G02Y1318044I-900J1202D01*
G03X221278I600J800D01*
G02Y1315640I900J-1202D01*
G37*
G36*
G01X269722Y1309313D02*
G03X268522I-600J-800D01*
G02Y1311717I-900J1202D01*
G03X269722I600J800D01*
G02Y1309313I900J-1202D01*
G37*
G36*
G01X258681D02*
G03X257481I-600J-800D01*
G02Y1311717I-900J1202D01*
G03X258681I600J800D01*
G02Y1309313I900J-1202D01*
G37*
G36*
G01X245196Y1307722D02*
G03X243996I-600J-800D01*
G02Y1310126I-900J1202D01*
G03X245196I600J800D01*
G02Y1307722I900J-1202D01*
G37*
G36*
G01X237700D02*
G03X236500I-600J-800D01*
G02Y1310126I-900J1202D01*
G03X237700I600J800D01*
G02Y1307722I900J-1202D01*
G37*
G36*
G01X228877D02*
G03X227677I-600J-800D01*
G02Y1310126I-900J1202D01*
G03X228877I600J800D01*
G02Y1307722I900J-1202D01*
G37*
G36*
G01X221449D02*
G03X220249I-600J-800D01*
G02Y1310126I-900J1202D01*
G03X221449I600J800D01*
G02Y1307722I900J-1202D01*
G37*
G36*
G01X157849Y1306531D02*
G03X156649I-600J-800D01*
G02Y1308935I-900J1202D01*
G03X157849I600J800D01*
G02Y1306531I900J-1202D01*
G37*
G36*
G01X269722Y1301585D02*
G03X268522I-600J-800D01*
G02Y1303989I-900J1202D01*
G03X269722I600J800D01*
G02Y1301585I900J-1202D01*
G37*
G36*
G01X258681D02*
G03X257481I-600J-800D01*
G02Y1303989I-900J1202D01*
G03X258681I600J800D01*
G02Y1301585I900J-1202D01*
G37*
G36*
G01X245061Y1300773D02*
G03X243861I-600J-800D01*
G02Y1303177I-900J1202D01*
G03X245061I600J800D01*
G02Y1300773I900J-1202D01*
G37*
G36*
G01X237565D02*
G03X236365I-600J-800D01*
G02Y1303177I-900J1202D01*
G03X237565I600J800D01*
G02Y1300773I900J-1202D01*
G37*
G36*
G01X228742D02*
G03X227542I-600J-800D01*
G02Y1303177I-900J1202D01*
G03X228742I600J800D01*
G02Y1300773I900J-1202D01*
G37*
G36*
G01X221314D02*
G03X220114I-600J-800D01*
G02Y1303177I-900J1202D01*
G03X221314I600J800D01*
G02Y1300773I900J-1202D01*
G37*
G36*
G01X245061Y1293289D02*
G03X243861I-600J-800D01*
G02Y1295693I-900J1202D01*
G03X245061I600J800D01*
G02Y1293289I900J-1202D01*
G37*
G36*
G01X237565D02*
G03X236365I-600J-800D01*
G02Y1295693I-900J1202D01*
G03X237565I600J800D01*
G02Y1293289I900J-1202D01*
G37*
G36*
G01X228742D02*
G03X227542I-600J-800D01*
G02Y1295693I-900J1202D01*
G03X228742I600J800D01*
G02Y1293289I900J-1202D01*
G37*
G36*
G01X221314D02*
G03X220114I-600J-800D01*
G02Y1295693I-900J1202D01*
G03X221314I600J800D01*
G02Y1293289I900J-1202D01*
G37*
G36*
G01X269722Y1292248D02*
G03X268522I-600J-800D01*
G02Y1294652I-900J1202D01*
G03X269722I600J800D01*
G02Y1292248I900J-1202D01*
G37*
G36*
G01X258681D02*
G03X257481I-600J-800D01*
G02Y1294652I-900J1202D01*
G03X258681I600J800D01*
G02Y1292248I900J-1202D01*
G37*
G36*
G01X228742Y1286070D02*
G03X227542I-600J-800D01*
G02Y1288474I-900J1202D01*
G03X228742I600J800D01*
G02Y1286070I900J-1202D01*
G37*
G36*
G01X221314D02*
G03X220114I-600J-800D01*
G02Y1288474I-900J1202D01*
G03X221314I600J800D01*
G02Y1286070I900J-1202D01*
G37*
G36*
G01X269722Y1281743D02*
G03X268522I-600J-800D01*
G02Y1284147I-900J1202D01*
G03X269722I600J800D01*
G02Y1281743I900J-1202D01*
G37*
G36*
G01X258681D02*
G03X257481I-600J-800D01*
G02Y1284147I-900J1202D01*
G03X258681I600J800D01*
G02Y1281743I900J-1202D01*
G37*
G36*
G01X269722Y1271228D02*
G03X268522I-600J-800D01*
G02Y1273632I-900J1202D01*
G03X269722I600J800D01*
G02Y1271228I900J-1202D01*
G37*
G36*
G01X258681D02*
G03X257481I-600J-800D01*
G02Y1273632I-900J1202D01*
G03X258681I600J800D01*
G02Y1271228I900J-1202D01*
G37*
G36*
G01X169982Y1252727D02*
G02X170003Y1252205I-6597J-527D01*
G02X156766I-6618J0D01*
G02X169982Y1252727I6618J0D01*
G37*
G36*
G01X311259Y1199491D02*
G03X310059I-600J-800D01*
G02Y1201895I-900J1202D01*
G03X311259I600J800D01*
G02Y1199491I900J-1202D01*
G37*
G36*
G01X302791D02*
G03X301591I-600J-800D01*
G02Y1201895I-900J1202D01*
G03X302791I600J800D01*
G02Y1199491I900J-1202D01*
G37*
G36*
G01X320036Y1199490D02*
G03X318836I-600J-800D01*
G02Y1201894I-900J1202D01*
G03X320036I600J800D01*
G02Y1199490I900J-1202D01*
G37*
G36*
G01X286282Y1199420D02*
G03X285082I-600J-800D01*
G02Y1201824I-900J1202D01*
G03X286282I600J800D01*
G02Y1199420I900J-1202D01*
G37*
G36*
G01X294821Y1199277D02*
G03X293621I-600J-800D01*
G02Y1201681I-900J1202D01*
G03X294821I600J800D01*
G02Y1199277I900J-1202D01*
G37*
G36*
G01X311259Y1191052D02*
G03X310059I-600J-800D01*
G02Y1193456I-900J1202D01*
G03X311259I600J800D01*
G02Y1191052I900J-1202D01*
G37*
G36*
G01X302791D02*
G03X301591I-600J-800D01*
G02Y1193456I-900J1202D01*
G03X302791I600J800D01*
G02Y1191052I900J-1202D01*
G37*
G36*
G01X320036Y1191051D02*
G03X318836I-600J-800D01*
G02Y1193455I-900J1202D01*
G03X320036I600J800D01*
G02Y1191051I900J-1202D01*
G37*
G36*
G01X286282Y1190981D02*
G03X285082I-600J-800D01*
G02Y1193385I-900J1202D01*
G03X286282I600J800D01*
G02Y1190981I900J-1202D01*
G37*
G36*
G01X294821Y1190838D02*
G03X293621I-600J-800D01*
G02Y1193242I-900J1202D01*
G03X294821I600J800D01*
G02Y1190838I900J-1202D01*
G37*
G36*
G01X311259Y1183324D02*
G03X310059I-600J-800D01*
G02Y1185728I-900J1202D01*
G03X311259I600J800D01*
G02Y1183324I900J-1202D01*
G37*
G36*
G01X302791D02*
G03X301591I-600J-800D01*
G02Y1185728I-900J1202D01*
G03X302791I600J800D01*
G02Y1183324I900J-1202D01*
G37*
G36*
G01X320036Y1183323D02*
G03X318836I-600J-800D01*
G02Y1185727I-900J1202D01*
G03X320036I600J800D01*
G02Y1183323I900J-1202D01*
G37*
G36*
G01X286282Y1183253D02*
G03X285082I-600J-800D01*
G02Y1185657I-900J1202D01*
G03X286282I600J800D01*
G02Y1183253I900J-1202D01*
G37*
G36*
G01X294821Y1183110D02*
G03X293621I-600J-800D01*
G02Y1185514I-900J1202D01*
G03X294821I600J800D01*
G02Y1183110I900J-1202D01*
G37*
G36*
G01X244777Y1144718D02*
G03X243577I-600J-800D01*
G02Y1147122I-900J1202D01*
G03X244777I600J800D01*
G02Y1144718I900J-1202D01*
G37*
G36*
G01X234809D02*
G03X233609I-600J-800D01*
G02Y1147122I-900J1202D01*
G03X234809I600J800D01*
G02Y1144718I900J-1202D01*
G37*
G36*
G01X253533Y1144574D02*
G03X252333I-600J-800D01*
G02Y1146978I-900J1202D01*
G03X253533I600J800D01*
G02Y1144574I900J-1202D01*
G37*
G36*
G01X262573Y1144431D02*
G03X261373I-600J-800D01*
G02Y1146835I-900J1202D01*
G03X262573I600J800D01*
G02Y1144431I900J-1202D01*
G37*
G36*
G01X271921Y1144289D02*
G03X270721I-600J-800D01*
G02Y1146693I-900J1202D01*
G03X271921I600J800D01*
G02Y1144289I900J-1202D01*
G37*
G36*
G01X244777Y1134213D02*
G03X243577I-600J-800D01*
G02Y1136617I-900J1202D01*
G03X244777I600J800D01*
G02Y1134213I900J-1202D01*
G37*
G36*
G01X234809D02*
G03X233609I-600J-800D01*
G02Y1136617I-900J1202D01*
G03X234809I600J800D01*
G02Y1134213I900J-1202D01*
G37*
G36*
G01X253533Y1134069D02*
G03X252333I-600J-800D01*
G02Y1136473I-900J1202D01*
G03X253533I600J800D01*
G02Y1134069I900J-1202D01*
G37*
G36*
G01X262573Y1133926D02*
G03X261373I-600J-800D01*
G02Y1136330I-900J1202D01*
G03X262573I600J800D01*
G02Y1133926I900J-1202D01*
G37*
G36*
G01X271921Y1133784D02*
G03X270721I-600J-800D01*
G02Y1136188I-900J1202D01*
G03X271921I600J800D01*
G02Y1133784I900J-1202D01*
G37*
G36*
G01X244777Y1123698D02*
G03X243577I-600J-800D01*
G02Y1126102I-900J1202D01*
G03X244777I600J800D01*
G02Y1123698I900J-1202D01*
G37*
G36*
G01X234809D02*
G03X233609I-600J-800D01*
G02Y1126102I-900J1202D01*
G03X234809I600J800D01*
G02Y1123698I900J-1202D01*
G37*
G36*
G01X253533Y1123554D02*
G03X252333I-600J-800D01*
G02Y1125958I-900J1202D01*
G03X253533I600J800D01*
G02Y1123554I900J-1202D01*
G37*
G36*
G01X262573Y1123411D02*
G03X261373I-600J-800D01*
G02Y1125815I-900J1202D01*
G03X262573I600J800D01*
G02Y1123411I900J-1202D01*
G37*
G36*
G01X271921Y1123269D02*
G03X270721I-600J-800D01*
G02Y1125673I-900J1202D01*
G03X271921I600J800D01*
G02Y1123269I900J-1202D01*
G37*
G36*
G01X169982Y1077727D02*
G02X170003Y1077205I-6597J-527D01*
G02X156766I-6618J0D01*
G02X169982Y1077727I6618J0D01*
G37*
G36*
G01X123239Y1083805D02*
G02X116601I-3319J-1640D01*
G03X115705Y1085248I-896J443D01*
G01X107226D01*
X106943Y1084965D01*
G03X107484Y1083272I707J-707D01*
G02X105754Y1081542I-249J-1481D01*
G03X104061Y1082083I-986J-166D01*
G01X101867Y1079890D01*
X96684D01*
G02Y1083692I0J1901D01*
G01X100291D01*
X105650Y1089052D01*
X115720D01*
G03X116613Y1090501I0J1000D01*
G02X122819Y1089862I3307J1664D01*
G01X122710Y1089726D01*
Y1089552D01*
G03X123210Y1089052I500J0D01*
G01X123507D01*
X126446Y1091991D01*
Y1111381D01*
X136137Y1121071D01*
G03X136276Y1121513I-353J354D01*
G02X139268Y1118521I3644J652D01*
G03X138826Y1118382I-88J-492D01*
G01X130250Y1109805D01*
Y1090415D01*
X125083Y1085248D01*
X124135D01*
G03X123239Y1083805I0J-1000D01*
G37*
G36*
G01X320140Y1032516D02*
G03X318940I-600J-800D01*
G02Y1034920I-900J1202D01*
G03X320140I600J800D01*
G02Y1032516I900J-1202D01*
G37*
G36*
G01X309099D02*
G03X307899I-600J-800D01*
G02Y1034920I-900J1202D01*
G03X309099I600J800D01*
G02Y1032516I900J-1202D01*
G37*
G36*
G01X320270Y1025879D02*
G03X319070I-600J-800D01*
G02Y1028283I-900J1202D01*
G03X320270I600J800D01*
G02Y1025879I900J-1202D01*
G37*
G36*
G01X309229D02*
G03X308029I-600J-800D01*
G02Y1028283I-900J1202D01*
G03X309229I600J800D01*
G02Y1025879I900J-1202D01*
G37*
G36*
G01X320335Y1019455D02*
G03X319135I-600J-800D01*
G02Y1021859I-900J1202D01*
G03X320335I600J800D01*
G02Y1019455I900J-1202D01*
G37*
G36*
G01X309294D02*
G03X308094I-600J-800D01*
G02Y1021859I-900J1202D01*
G03X309294I600J800D01*
G02Y1019455I900J-1202D01*
G37*
G36*
G01X320284Y1012892D02*
G03X319084I-600J-800D01*
G02Y1015296I-900J1202D01*
G03X320284I600J800D01*
G02Y1012892I900J-1202D01*
G37*
G36*
G01X309243D02*
G03X308043I-600J-800D01*
G02Y1015296I-900J1202D01*
G03X309243I600J800D01*
G02Y1012892I900J-1202D01*
G37*
G36*
G01X320219Y1006101D02*
G03X319019I-600J-800D01*
G02Y1008505I-900J1202D01*
G03X320219I600J800D01*
G02Y1006101I900J-1202D01*
G37*
G36*
G01X309178D02*
G03X307978I-600J-800D01*
G02Y1008505I-900J1202D01*
G03X309178I600J800D01*
G02Y1006101I900J-1202D01*
G37*
G36*
G01X320415Y1000084D02*
G03X319215I-600J-800D01*
G02Y1002488I-900J1202D01*
G03X320415I600J800D01*
G02Y1000084I900J-1202D01*
G37*
G36*
G01X309374D02*
G03X308174I-600J-800D01*
G02Y1002488I-900J1202D01*
G03X309374I600J800D01*
G02Y1000084I900J-1202D01*
G37*
G54D32*
X106958Y26285D03*
X101430Y41803D03*
X107405Y49898D03*
X107037Y34687D03*
X104350Y62293D03*
X109054Y58250D03*
X108672Y86150D03*
X157558Y51426D03*
X331403Y51409D03*
X333889Y56021D03*
X338227Y61559D03*
X348289Y50863D03*
X345089Y56190D03*
X340373Y51579D03*
X106836Y376461D03*
X106709Y391219D03*
X109475Y434743D03*
X115139Y849240D03*
X156865Y401207D03*
X159019Y439268D03*
X156610Y751063D03*
X175989Y944537D03*
X176011Y936829D03*
X175359Y963486D03*
X175561Y955964D03*
X175897Y1023997D03*
X335522Y404033D03*
X323313Y418313D03*
X326196Y413982D03*
X328950Y409216D03*
X320980Y423225D03*
X319305Y582111D03*
X317724Y588250D03*
X320380Y576491D03*
X331568Y752967D03*
X339012Y752859D03*
X329336Y762693D03*
X334010Y758588D03*
X327524Y758020D03*
X362236Y324983D03*
X342097Y401684D03*
X344109Y751809D03*
X45581Y1278420D03*
X45413Y1283724D03*
X45244Y1289067D03*
X45350Y1299697D03*
X45267Y1294203D03*
X45281Y1310893D03*
X45244Y1305787D03*
X46980Y1335843D03*
Y1325843D03*
Y1315843D03*
Y1320843D03*
Y1330843D03*
Y1345843D03*
Y1340843D03*
X54543Y1308995D03*
X95236Y1453321D03*
X106962Y1434041D03*
X106921Y1419492D03*
X106763Y1444599D03*
X107006Y1452651D03*
X107355Y1770437D03*
X107373Y1780544D03*
X106819Y1802230D03*
X108819Y1824470D03*
X159192Y1451105D03*
X159526Y1483434D03*
X156452Y1800821D03*
X226573Y2031480D03*
X236541D03*
X226573Y2020965D03*
X236541D03*
X242582D03*
Y2031480D03*
X231541Y2020965D03*
X221573D03*
X231541Y2031480D03*
X221573D03*
X226573Y2059050D03*
X236541Y2051322D03*
Y2059050D03*
X226573Y2041985D03*
Y2051322D03*
X236541Y2041985D03*
X242582Y2059050D03*
Y2051322D03*
Y2041985D03*
X231541D03*
X221573Y2051322D03*
Y2041985D03*
X231541Y2059050D03*
Y2051322D03*
X221573Y2059050D03*
X236541Y2067489D03*
X226573D03*
X242582D03*
X221573D03*
X231541D03*
X247582Y2031480D03*
Y2020965D03*
X260337D03*
Y2031480D03*
X267115Y2020965D03*
Y2031480D03*
X255337D03*
Y2020965D03*
X247582Y2041985D03*
Y2051322D03*
Y2059050D03*
X260337Y2051322D03*
Y2059050D03*
Y2041985D03*
X267115D03*
Y2059050D03*
Y2051322D03*
X255337Y2041985D03*
Y2059050D03*
Y2051322D03*
X260337Y2067489D03*
X247582D03*
X267115D03*
X255337D03*
X272115Y2031480D03*
Y2020965D03*
Y2051322D03*
Y2059050D03*
Y2041985D03*
Y2067489D03*
X312077Y1575871D03*
X292614Y1864565D03*
X323720Y1570924D03*
X333474Y1566686D03*
X335963Y1573797D03*
X332399Y1926787D03*
X345537Y1916558D03*
X344402Y1911123D03*
X340336Y1922409D03*
X107351Y1093484D03*
X107215Y1072208D03*
X108779Y1105760D03*
X105152Y1118381D03*
X112503Y1115860D03*
X156854Y1101031D03*
X159382Y1136151D03*
X158456Y1129045D03*
X312527Y1162266D03*
X312698Y1172804D03*
X323403D03*
X49441Y1238962D03*
X59127Y1257647D03*
X70340Y1328203D03*
X327452Y1279447D03*
X329619Y1284016D03*
X327932Y1289221D03*
X374681Y1365620D03*
G54D28*
X15547Y707364D03*
X25389D03*
X15547Y715238D03*
Y730986D03*
X25389Y715238D03*
Y730986D03*
X15547Y738860D03*
X33263Y703427D03*
Y711301D03*
Y719175D03*
Y727049D03*
X15547Y959333D03*
Y967207D03*
Y975081D03*
X25389D03*
X33263Y979018D03*
X15551Y1254606D03*
Y1262480D03*
X25393Y1254606D03*
X15551Y1270354D03*
Y1278228D03*
Y1286102D03*
X25393Y1278228D03*
X15551Y1293976D03*
Y1301850D03*
Y1309724D03*
X25393Y1293976D03*
Y1301850D03*
Y1309724D03*
X15551Y1317598D03*
Y1325472D03*
Y1333346D03*
X25393Y1325472D03*
Y1333346D03*
Y1356968D03*
X15551Y1372716D03*
Y1380590D03*
X25393Y1364842D03*
Y1380590D03*
Y1388464D03*
X33267Y1258543D03*
Y1266417D03*
Y1274291D03*
Y1282165D03*
Y1290039D03*
Y1297913D03*
Y1305787D03*
Y1313661D03*
Y1321535D03*
Y1329409D03*
Y1337283D03*
Y1353031D03*
Y1368779D03*
Y1376653D03*
G54D27*
X14073Y512197D03*
Y522000D03*
Y552000D03*
Y561803D03*
X65254Y529500D03*
Y539500D03*
X55254Y524500D03*
Y534500D03*
X65254Y549500D03*
X55254Y544500D03*
Y554500D03*
X14073Y1580004D03*
Y1570201D03*
Y1610004D03*
Y1619807D03*
X65254Y1577504D03*
Y1587504D03*
Y1597504D03*
X55254Y1582504D03*
Y1592504D03*
Y1602504D03*
X65254Y1607504D03*
X55254Y1612504D03*
G54D26*
X22756Y125629D03*
X22480Y328649D03*
X22756Y1878630D03*
Y1960629D03*
Y2035629D03*
G54D33*
X253385Y21890D03*
Y32520D03*
X263385Y21890D03*
Y32520D03*
X253385Y196890D03*
X263385D03*
X253385Y207520D03*
X263385D03*
X273385Y21890D03*
Y32520D03*
X283385Y21890D03*
Y32520D03*
X273385Y196890D03*
X283385D03*
X273385Y207520D03*
X283385D03*
X293385Y21890D03*
Y32520D03*
X303385Y21890D03*
Y32520D03*
X313385D03*
Y21890D03*
X293385Y196890D03*
X303385D03*
X313385D03*
X293385Y207520D03*
X303385D03*
X313385D03*
X337165Y24705D03*
X323385Y32520D03*
Y21890D03*
Y196890D03*
Y207520D03*
X342165Y19705D03*
X362165D03*
X253385Y371890D03*
X263385D03*
X253385Y382520D03*
X263385D03*
X253386Y546890D03*
Y557520D03*
X263386Y546890D03*
Y557520D03*
X253386Y721890D03*
Y732520D03*
X263386Y721890D03*
Y732520D03*
X253385Y896890D03*
X263385D03*
X253385Y907520D03*
X263385D03*
X273385Y371890D03*
X283385D03*
X273385Y382520D03*
X283385D03*
X273386Y546890D03*
Y557520D03*
X283386Y546890D03*
Y557520D03*
X273386Y721890D03*
Y732520D03*
X283386Y721890D03*
Y732520D03*
X273385Y896890D03*
X283385D03*
X273385Y907520D03*
X283385D03*
X293385Y371890D03*
X303385D03*
X313385D03*
X293385Y382520D03*
X303385D03*
X313385D03*
X293386Y546890D03*
Y557520D03*
X303386Y546890D03*
Y557520D03*
X313386D03*
Y546890D03*
X293386Y721890D03*
Y732520D03*
X303386Y721890D03*
Y732520D03*
X313386D03*
Y721890D03*
X293385Y896890D03*
X303385D03*
X313385D03*
X293385Y907520D03*
X303385D03*
X313385D03*
X323385Y371890D03*
Y382520D03*
X323386Y557520D03*
Y546890D03*
Y732520D03*
Y721890D03*
X323385Y896890D03*
X352165Y369705D03*
X362165D03*
X352165Y379705D03*
X357165Y374705D03*
Y384705D03*
X362165Y379705D03*
X347166Y559705D03*
X352166Y554705D03*
X342166Y719705D03*
X352166D03*
Y729705D03*
X357166Y724705D03*
X362166Y719705D03*
Y729705D03*
X357166Y734705D03*
X347165Y909705D03*
X352165Y904705D03*
X253385Y1421890D03*
Y1432520D03*
X263385Y1421890D03*
Y1432520D03*
X253385Y1596890D03*
X263385D03*
X253385Y1607520D03*
X263385D03*
X253385Y1771890D03*
X263385D03*
X253385Y1782520D03*
X263385D03*
X253385Y1946890D03*
Y1957520D03*
X263385Y1946890D03*
Y1957520D03*
X273385Y1421890D03*
Y1432520D03*
X283385Y1421890D03*
Y1432520D03*
X273385Y1596890D03*
X283385D03*
X273385Y1607520D03*
X283385D03*
X273385Y1771890D03*
X283385D03*
X273385Y1782520D03*
X283385D03*
X273385Y1946890D03*
Y1957520D03*
X283385Y1946890D03*
Y1957520D03*
X293385Y1421890D03*
Y1432520D03*
X303385Y1421890D03*
Y1432520D03*
X313385D03*
Y1421890D03*
X293385Y1596890D03*
X303385D03*
X313385D03*
X293385Y1607520D03*
X303385D03*
X313385D03*
X293385Y1771890D03*
X303385D03*
X313385D03*
X293385Y1782520D03*
X303385D03*
X313385D03*
X293385Y1946890D03*
Y1957520D03*
X303385Y1946890D03*
Y1957520D03*
X313385D03*
Y1946890D03*
X323385Y1432520D03*
Y1421890D03*
Y1596890D03*
Y1607520D03*
Y1957520D03*
Y1946890D03*
X347165Y1599705D03*
X342165Y1604705D03*
X352165D03*
X253385Y1071890D03*
X263385D03*
X253385Y1082520D03*
X263385D03*
X253385Y1246890D03*
Y1257520D03*
X263385Y1246890D03*
Y1257520D03*
X273385Y1071890D03*
X283385D03*
X273385Y1082520D03*
X283385D03*
X273385Y1246890D03*
Y1257520D03*
X283385Y1246890D03*
Y1257520D03*
X293385Y1071890D03*
X303385D03*
X313385D03*
X293385Y1082520D03*
X303385D03*
X313385D03*
X293385Y1246890D03*
Y1257520D03*
X303385Y1246890D03*
Y1257520D03*
X313385D03*
Y1246890D03*
X323385Y1071890D03*
X337165Y1074705D03*
X323385Y1082520D03*
X342165Y1069705D03*
X352165D03*
X362165D03*
X357165Y1074705D03*
Y1084705D03*
X362165Y1079705D03*
G54D31*
X119920Y18071D03*
Y28071D03*
Y38071D03*
Y48071D03*
Y58071D03*
Y88071D03*
Y218071D03*
Y228071D03*
Y238071D03*
Y248071D03*
Y258071D03*
Y268071D03*
Y278071D03*
Y288071D03*
Y298071D03*
Y308071D03*
Y318071D03*
Y328071D03*
X139920Y28071D03*
Y18071D03*
Y58071D03*
Y48071D03*
Y38071D03*
Y68071D03*
Y228071D03*
Y218071D03*
Y248071D03*
Y238071D03*
Y268071D03*
Y258071D03*
Y298071D03*
Y288071D03*
Y278071D03*
Y318071D03*
Y308071D03*
Y328071D03*
X119920Y366102D03*
Y376102D03*
Y386102D03*
Y566102D03*
Y576102D03*
Y586102D03*
Y596102D03*
Y606102D03*
Y616102D03*
Y626102D03*
Y636102D03*
Y646102D03*
Y656102D03*
Y666102D03*
Y676102D03*
Y724134D03*
Y734134D03*
Y744134D03*
Y754134D03*
Y784134D03*
Y914134D03*
Y924134D03*
Y934134D03*
Y944134D03*
Y954134D03*
X139920Y366102D03*
Y396102D03*
Y386102D03*
Y376102D03*
Y416102D03*
Y566102D03*
Y586102D03*
Y576102D03*
Y606102D03*
Y596102D03*
Y636102D03*
Y626102D03*
Y616102D03*
Y656102D03*
Y646102D03*
Y676102D03*
Y666102D03*
Y734134D03*
Y724134D03*
Y714134D03*
Y754134D03*
Y744134D03*
Y764134D03*
Y924134D03*
Y914134D03*
Y944134D03*
Y934134D03*
Y954134D03*
X119920Y1420197D03*
Y1430197D03*
Y1440197D03*
Y1450197D03*
Y1480197D03*
Y1768228D03*
Y1778228D03*
Y1788228D03*
Y1798228D03*
Y1828228D03*
Y1958228D03*
Y1968228D03*
Y1978228D03*
Y1988228D03*
Y1998228D03*
Y2008228D03*
Y2018228D03*
Y2028228D03*
Y2038228D03*
Y2048228D03*
Y2058228D03*
Y2068228D03*
X139920Y1430197D03*
Y1420197D03*
Y1460197D03*
Y1450197D03*
Y1440197D03*
Y1620197D03*
Y1610197D03*
Y1650197D03*
Y1640197D03*
Y1630197D03*
Y1670197D03*
Y1660197D03*
Y1700197D03*
Y1690197D03*
Y1680197D03*
Y1720197D03*
Y1710197D03*
Y1768228D03*
Y1798228D03*
Y1788228D03*
Y1778228D03*
Y1828228D03*
Y1958228D03*
Y1988228D03*
Y1978228D03*
Y1968228D03*
Y2008228D03*
Y1998228D03*
Y2038228D03*
Y2028228D03*
Y2018228D03*
Y2058228D03*
Y2048228D03*
Y2068228D03*
X119920Y1072165D03*
Y1102165D03*
Y1112165D03*
Y1122165D03*
Y1132165D03*
X139920Y1072165D03*
Y1092165D03*
Y1082165D03*
Y1112165D03*
Y1102165D03*
Y1132165D03*
Y1262165D03*
Y1282165D03*
Y1272165D03*
Y1312165D03*
Y1302165D03*
Y1292165D03*
Y1332165D03*
Y1322165D03*
Y1362165D03*
Y1352165D03*
Y1342165D03*
Y1372165D03*
G54D30*
X64979Y35500D03*
Y45500D03*
X54979Y40500D03*
X64979Y65500D03*
X54979Y60500D03*
Y70500D03*
X64979Y380500D03*
Y390500D03*
X54979Y385500D03*
X64979Y400500D03*
Y410500D03*
X54979Y405500D03*
Y415500D03*
X189762Y73105D03*
X190289Y152050D03*
X190357Y247568D03*
X190817Y331786D03*
X203542Y73105D03*
X204069Y152050D03*
X204137Y247568D03*
X189761Y421732D03*
X190553Y506517D03*
X192888Y598130D03*
X190816Y681645D03*
X191846Y774526D03*
X191606Y856244D03*
X196311Y947202D03*
X203541Y421732D03*
X204333Y506517D03*
X206668Y598130D03*
X204596Y681645D03*
X205626Y774526D03*
X205386Y856244D03*
X210091Y947202D03*
X189463Y1474162D03*
X191079Y1557277D03*
X192143Y1648177D03*
X191607Y1731351D03*
X191530Y1823227D03*
X190289Y1900420D03*
X192125Y1998730D03*
X191530Y2043388D03*
X203243Y1474162D03*
X204859Y1557277D03*
X205923Y1648177D03*
X205387Y1731351D03*
X205310Y1823227D03*
X204069Y1900420D03*
X205905Y1998730D03*
X205310Y2043388D03*
X191250Y1122856D03*
X191342Y1206233D03*
X191846Y1299104D03*
X205030Y1122856D03*
X205122Y1206233D03*
X205626Y1299104D03*
X190552Y1380966D03*
X204332D03*
G54D38*
X23402Y1668874D03*
Y1718480D03*
Y1768087D03*
Y1817693D03*
X45056Y1668874D03*
Y1685410D03*
Y1701945D03*
Y1718480D03*
Y1735016D03*
Y1751551D03*
Y1768087D03*
Y1784622D03*
Y1817693D03*
Y1801158D03*
G54D24*
X30473Y102007D03*
Y137440D03*
G54D37*
Y1855008D03*
Y1890441D03*
Y1937007D03*
Y1972440D03*
Y2012007D03*
Y2047440D03*
G54D29*
X20468Y696341D03*
G54D34*
X307087Y127164D03*
Y827164D03*
Y477164D03*
Y2043503D03*
Y1693503D03*
Y1343503D03*
G54D35*
X307086Y308267D03*
G54D22*
X29979Y75500D03*
Y166500D03*
Y211500D03*
Y239500D03*
G54D25*
X373385Y32520D03*
Y207520D03*
Y382520D03*
X373386Y557520D03*
Y732520D03*
X373385Y907520D03*
Y1607520D03*
Y1957520D03*
Y1082520D03*
Y1257520D03*
G54D36*
X359842Y253780D03*
Y428779D03*
Y603779D03*
Y778780D03*
Y953780D03*
Y1478780D03*
Y1653780D03*
Y1828779D03*
Y2003780D03*
Y1128779D03*
Y1303780D03*
G54D23*
X30254Y514500D03*
Y559500D03*
Y1572504D03*
Y1617504D03*
%LPD*%
G75*
G54D10*
G01X111017Y419566D02*
Y424690D01*
X117506Y431179D01*
X148139D01*
X150507Y428811D01*
X221508D01*
X258946Y466249D01*
X262575D01*
X265722Y463102D01*
G01X158807Y432969D02*
X219785D01*
X257131Y470315D01*
X262372D01*
X265737Y473680D01*
X25219Y18752D03*
X3001Y52034D03*
Y100034D03*
Y150034D03*
Y200034D03*
Y250034D03*
Y300034D03*
Y350034D03*
Y400034D03*
Y450034D03*
Y500034D03*
X13441Y495961D03*
X3001Y550034D03*
X10914Y578848D03*
X15984Y578849D03*
X3001Y600034D03*
Y650034D03*
Y700034D03*
Y750034D03*
Y800034D03*
Y850034D03*
Y900034D03*
Y950034D03*
Y1000034D03*
Y1050034D03*
Y1100034D03*
Y1150034D03*
Y1200034D03*
Y1250034D03*
Y1300034D03*
Y1350034D03*
Y1400034D03*
Y1450034D03*
Y1500034D03*
Y1550034D03*
X11541Y1562330D03*
X3006Y1594602D03*
X3012Y1610165D03*
X3001Y1650034D03*
X11153Y1638435D03*
X16552Y1638005D03*
X3001Y1700034D03*
Y1750034D03*
Y1800034D03*
Y1850034D03*
Y1900034D03*
Y1950034D03*
Y2000034D03*
Y2050034D03*
X48433Y866179D03*
X48467Y869278D03*
X26833Y2067866D03*
X60815Y1019026D03*
X63577Y1019115D03*
X57458Y1253378D03*
X54543Y1296513D03*
X67568Y1296654D03*
X54130Y1313763D03*
X55544Y1770835D03*
X55080Y1762982D03*
X54948Y1755171D03*
X56425Y1778371D03*
X70376Y1796383D03*
X75219Y18752D03*
X97417Y32853D03*
Y37438D03*
X97536Y376580D03*
X97457Y371909D03*
X97985Y391220D03*
X97643Y396024D03*
X94347Y421562D03*
X96308Y696622D03*
X76446Y1014871D03*
X79499D03*
X96904Y1067515D03*
X96948Y1092036D03*
X96949Y1087095D03*
X96774Y1072226D03*
X96684Y1081791D03*
X96510Y1395382D03*
X97403Y1424340D03*
X97825Y1419492D03*
X96993Y1443743D03*
X96996Y1438980D03*
X97465Y1447919D03*
X88837Y1771103D03*
X91460Y1765062D03*
X93771Y1748227D03*
X80376Y1772098D03*
Y1768566D03*
X75376Y1796236D03*
X80376Y1796163D03*
X85376Y1796236D03*
X80376Y1775609D03*
X76833Y2067866D03*
X106335Y22580D03*
X108082Y38899D03*
X102646Y49461D03*
X107263Y72244D03*
X104116Y82557D03*
X101990Y426104D03*
X111017Y419566D03*
X102960Y672823D03*
X112836Y769122D03*
X105395Y972040D03*
X102611Y972220D03*
X98652Y1096403D03*
X105684Y1125919D03*
X105455Y1472894D03*
X108574Y1463389D03*
X99103Y1765722D03*
X99068Y1760827D03*
X99047Y1785571D03*
X98873Y1780542D03*
X99294Y1789947D03*
X105669Y1815227D03*
X108819Y1812118D03*
X109991Y2083607D03*
X125219Y3002D03*
X162384Y56744D03*
X161742Y72497D03*
X162586Y68130D03*
X158901Y85017D03*
X169500Y126110D03*
Y118626D03*
Y111407D03*
X166500D03*
Y118626D03*
Y126110D03*
X169329Y140623D03*
X169500Y132705D03*
X169329Y148066D03*
X166329D03*
X166500Y132705D03*
X166329Y140623D03*
X169329Y156102D03*
Y163621D03*
X166329D03*
Y156102D03*
X161377Y407575D03*
X161257Y420869D03*
X158807Y432969D03*
X159430Y461714D03*
X156430D03*
X159430Y483012D03*
X159259Y490930D03*
X159430Y468933D03*
Y476417D03*
X156430D03*
Y468933D03*
X156259Y490930D03*
X156430Y483012D03*
X159259Y513928D03*
Y498373D03*
Y506409D03*
X156259D03*
Y498373D03*
Y513928D03*
X161826Y756757D03*
X161131Y774878D03*
X161644Y764231D03*
X158956Y780982D03*
X158444Y822725D03*
X165872D03*
X162872D03*
X155444D03*
X165872Y830209D03*
X158444D03*
X165872Y836804D03*
X158444D03*
X165701Y844722D03*
X158273D03*
X165701Y852165D03*
X158273D03*
X155273D03*
X162701D03*
X155273Y844722D03*
X162701D03*
X155444Y836804D03*
X162872D03*
X155444Y830209D03*
X162872D03*
X165701Y860201D03*
X158273D03*
X165701Y867720D03*
X158273D03*
X155273D03*
X162701D03*
X155273Y860201D03*
X162701D03*
X164539Y1116135D03*
X162140Y1106853D03*
X156124Y1176256D03*
X163552D03*
Y1183740D03*
Y1190335D03*
X156124D03*
Y1183740D03*
X163552Y1169037D03*
X156124D03*
X153124D03*
X160552D03*
X153124Y1183740D03*
Y1190335D03*
X160552D03*
Y1183740D03*
Y1176256D03*
X153124D03*
X169375Y1183740D03*
Y1190335D03*
Y1176256D03*
X163381Y1198253D03*
X155953D03*
X152953D03*
X160381D03*
X169204D03*
X163099Y1457084D03*
X162524Y1462651D03*
X162242Y1471380D03*
X159216Y1477124D03*
X154109Y1499221D03*
X161537D03*
Y1506440D03*
X170360D03*
X154109D03*
X157109D03*
X164537D03*
Y1499221D03*
X157109D03*
X153938Y1528437D03*
X154109Y1513924D03*
Y1520519D03*
X170360Y1513924D03*
Y1520519D03*
X161537D03*
Y1513924D03*
X161366Y1528437D03*
X170189D03*
X164366D03*
X164537Y1513924D03*
Y1520519D03*
X157109D03*
Y1513924D03*
X156938Y1528437D03*
X153938Y1535880D03*
Y1543916D03*
Y1551435D03*
X170189Y1535880D03*
Y1543916D03*
X161366Y1535880D03*
Y1543916D03*
Y1551435D03*
X170189D03*
X164366D03*
Y1543916D03*
Y1535880D03*
X156938Y1551435D03*
Y1543916D03*
Y1535880D03*
X163250Y1815631D03*
X162140Y1807740D03*
X159075Y1825087D03*
X155091Y1866003D03*
X162519D03*
X159519D03*
X152091D03*
X155091Y1880706D03*
Y1887301D03*
X162519D03*
Y1880706D03*
Y1873222D03*
X155091D03*
X152091D03*
X168342D03*
X159519D03*
Y1880706D03*
Y1887301D03*
X168342D03*
Y1880706D03*
X152091Y1887301D03*
Y1880706D03*
X154920Y1902662D03*
Y1910698D03*
X162348Y1902662D03*
Y1910698D03*
X154920Y1895219D03*
X162348D03*
X168171D03*
X159348D03*
X151920D03*
X159348Y1910698D03*
Y1902662D03*
X168171Y1910698D03*
Y1902662D03*
X151920Y1910698D03*
Y1902662D03*
X154920Y1918217D03*
X162348D03*
X168171D03*
X159348D03*
X151920D03*
X159991Y2083607D03*
X175219Y3002D03*
X176928Y126110D03*
Y118626D03*
Y111407D03*
X173928D03*
Y118626D03*
Y126110D03*
X176757Y140623D03*
X176928Y132705D03*
X176757Y148066D03*
X173757D03*
X173928Y132705D03*
X173757Y140623D03*
X176757Y156102D03*
Y163621D03*
X173757D03*
Y156102D03*
X175033Y261594D03*
Y268813D03*
X178033D03*
Y261594D03*
X175033Y282892D03*
X174862Y290810D03*
Y298253D03*
X175033Y276297D03*
X178033D03*
X177862Y298253D03*
Y290810D03*
X178033Y282892D03*
X174862Y313808D03*
Y306289D03*
X177862D03*
Y313808D03*
X182191Y822725D03*
X174695D03*
X171695D03*
X179191D03*
X174524Y844722D03*
Y852165D03*
X182191Y830209D03*
X174695D03*
X182191Y836804D03*
X174695D03*
X182020Y844722D03*
Y852165D03*
X179020D03*
Y844722D03*
X171695Y836804D03*
X179191D03*
X171695Y830209D03*
X179191D03*
X171524Y852165D03*
Y844722D03*
X174524Y860201D03*
Y867720D03*
X182020Y860201D03*
Y867720D03*
X179020D03*
Y860201D03*
X171524Y867720D03*
Y860201D03*
X184284Y948331D03*
X184196Y967371D03*
X175135Y972490D03*
X184632Y983423D03*
X175022Y980281D03*
X175742Y989958D03*
X175449Y997660D03*
X184353Y1001556D03*
X184118Y1019280D03*
X188385Y1020810D03*
X175698Y1008730D03*
X175473Y1016296D03*
X179871Y1176256D03*
Y1190335D03*
Y1183740D03*
X172375Y1176256D03*
Y1190335D03*
Y1183740D03*
X176871D03*
Y1190335D03*
Y1176256D03*
X179700Y1198253D03*
X172204D03*
X176700D03*
X177856Y1506440D03*
X173360D03*
X180856D03*
X177856Y1513924D03*
Y1520519D03*
X177685Y1528437D03*
X173189D03*
X173360Y1520519D03*
Y1513924D03*
X180685Y1528437D03*
X180856Y1520519D03*
Y1513924D03*
X177685Y1535880D03*
Y1543916D03*
Y1551435D03*
X173189D03*
Y1543916D03*
Y1535880D03*
X180685Y1551435D03*
Y1543916D03*
Y1535880D03*
X178838Y1880706D03*
Y1887301D03*
Y1873222D03*
X171342Y1880706D03*
Y1887301D03*
Y1873222D03*
X175838D03*
Y1887301D03*
Y1880706D03*
X178667Y1902662D03*
Y1910698D03*
Y1895219D03*
X171171Y1902662D03*
Y1910698D03*
Y1895219D03*
X175667D03*
Y1910698D03*
Y1902662D03*
X178667Y1918217D03*
X171171D03*
X175667D03*
X219131Y1663167D03*
Y1670386D03*
Y1684465D03*
Y1677870D03*
X218960Y1692383D03*
Y1699826D03*
Y1707862D03*
Y1715381D03*
X209991Y2083607D03*
X225219Y3002D03*
X237955Y56999D03*
X240955D03*
X237955Y64483D03*
X237784Y78996D03*
X237955Y71078D03*
X240955D03*
X240784Y78996D03*
X240955Y64483D03*
X237784Y94475D03*
Y101994D03*
Y86439D03*
X240784D03*
Y101994D03*
Y94475D03*
X241033Y244995D03*
X233537D03*
X224714Y237776D03*
Y244995D03*
X227714D03*
Y237776D03*
X236537Y244995D03*
X241033Y259074D03*
X240862Y266992D03*
Y274435D03*
X241033Y252479D03*
X233537Y259074D03*
X233366Y266992D03*
Y274435D03*
X224714Y259074D03*
X224543Y266992D03*
Y274435D03*
X233537Y252479D03*
X224714D03*
X227714D03*
X236537D03*
X227543Y274435D03*
Y266992D03*
X227714Y259074D03*
X236366Y274435D03*
Y266992D03*
X236537Y259074D03*
X240862Y289990D03*
Y282471D03*
X233366Y289990D03*
X224543D03*
X233366Y282471D03*
X224543D03*
X227543D03*
X236366D03*
X227543Y289990D03*
X236366D03*
X229548Y461083D03*
X232548D03*
X238371Y482381D03*
X238200Y490299D03*
X229548Y482381D03*
X229377Y490299D03*
X238371Y468302D03*
Y475786D03*
X229548Y468302D03*
Y475786D03*
X232548D03*
Y468302D03*
X241371Y475786D03*
Y468302D03*
X232377Y490299D03*
X232548Y482381D03*
X241200Y490299D03*
X241371Y482381D03*
X238200Y513297D03*
X229377D03*
X238200Y497742D03*
X229377D03*
X238200Y505778D03*
X229377D03*
X232377D03*
X241200D03*
X232377Y497742D03*
X241200D03*
X232377Y513297D03*
X241200D03*
X227963Y608108D03*
X235391D03*
X227963Y601513D03*
X235391D03*
Y594029D03*
X227963D03*
X230963D03*
X238391D03*
Y601513D03*
X230963D03*
X238391Y608108D03*
X230963D03*
X227792Y631505D03*
X235220D03*
X227792Y623469D03*
X235220D03*
X227792Y616026D03*
X235220D03*
X238220D03*
X230792D03*
X238220Y623469D03*
X230792D03*
X238220Y631505D03*
X230792D03*
X227792Y639024D03*
X235220D03*
X238220D03*
X230792D03*
X231339Y959673D03*
X238767D03*
Y967157D03*
Y973752D03*
X231339D03*
Y967157D03*
X238767Y952454D03*
X231339D03*
X234339D03*
X241767D03*
X234339Y967157D03*
Y973752D03*
X241767D03*
Y967157D03*
Y959673D03*
X234339D03*
X238596Y981670D03*
X231168D03*
X238596Y997149D03*
Y989113D03*
X231168Y997149D03*
Y989113D03*
X234168D03*
Y997149D03*
X241596Y989113D03*
Y997149D03*
X234168Y981670D03*
X241596D03*
X238596Y1004668D03*
X231168D03*
X234168D03*
X241596D03*
X235659Y1215296D03*
X228231D03*
X235659Y1207777D03*
Y1199741D03*
X228231Y1207777D03*
Y1199741D03*
X231231D03*
Y1207777D03*
X238659Y1199741D03*
Y1207777D03*
X231231Y1215296D03*
X238659D03*
X235382Y1670386D03*
X226559Y1663167D03*
Y1670386D03*
X222131D03*
X229559D03*
Y1663167D03*
X238382Y1670386D03*
X222131Y1663167D03*
X242878Y1670386D03*
X235382Y1677870D03*
X235211Y1692383D03*
X235382Y1684465D03*
X226559D03*
Y1677870D03*
X226388Y1692383D03*
X221960D03*
X222131Y1677870D03*
Y1684465D03*
X229388Y1692383D03*
X229559Y1677870D03*
Y1684465D03*
X238382D03*
X238211Y1692383D03*
X238382Y1677870D03*
X242878D03*
Y1684465D03*
X242707Y1692383D03*
X235211Y1699826D03*
X226388D03*
X235211Y1715381D03*
Y1707862D03*
X226388D03*
Y1715381D03*
X221960D03*
Y1707862D03*
X229388Y1715381D03*
Y1707862D03*
X238211D03*
Y1715381D03*
X221960Y1699826D03*
X229388D03*
X238211D03*
X242707D03*
Y1707862D03*
Y1715381D03*
X245451Y56999D03*
X248451D03*
X245451Y64483D03*
X245280Y78996D03*
X245451Y71078D03*
X248451D03*
X248280Y78996D03*
X248451Y64483D03*
X245280Y94475D03*
Y101994D03*
Y86439D03*
X248280D03*
Y101994D03*
Y94475D03*
X267627Y115559D03*
X256947Y128276D03*
X257125Y115559D03*
X267420Y147540D03*
X263086Y147675D03*
X244033Y244995D03*
Y252479D03*
X243862Y274435D03*
Y266992D03*
X244033Y259074D03*
X243862Y282471D03*
Y289990D03*
X265722Y463102D03*
X245867Y482381D03*
X245696Y490299D03*
X245867Y468302D03*
Y475786D03*
X248867D03*
Y468302D03*
X248696Y490299D03*
X248867Y482381D03*
X265737Y473680D03*
X245696Y513297D03*
Y497742D03*
Y505778D03*
X248696D03*
Y497742D03*
Y513297D03*
X264516Y497341D03*
X251710Y608108D03*
Y601513D03*
Y594029D03*
X244214Y608108D03*
Y601513D03*
Y594029D03*
X247214D03*
Y601513D03*
Y608108D03*
X254710Y594029D03*
Y601513D03*
Y608108D03*
X264433Y624321D03*
X267433D03*
X251539Y631505D03*
Y623469D03*
Y616026D03*
X244043Y631505D03*
Y623469D03*
Y616026D03*
X247043D03*
Y623469D03*
Y631505D03*
X254539Y616026D03*
Y623469D03*
Y631505D03*
X251539Y639024D03*
X244043D03*
X247043D03*
X254539D03*
X255837Y823626D03*
X255687Y812192D03*
X264181Y847354D03*
X255086Y959673D03*
Y973752D03*
Y967157D03*
X247590Y959673D03*
Y973752D03*
Y967157D03*
X250590D03*
Y973752D03*
Y959673D03*
X258086Y967157D03*
Y973752D03*
Y959673D03*
X254915Y981670D03*
Y997149D03*
Y989113D03*
X247419Y981670D03*
Y997149D03*
Y989113D03*
X250419D03*
Y997149D03*
Y981670D03*
X257915Y989113D03*
Y997149D03*
Y981670D03*
X254915Y1004668D03*
X247419D03*
X250419D03*
X257915D03*
X267194Y1191777D03*
X262559D03*
X251978Y1215296D03*
X244482D03*
X251978Y1207777D03*
Y1199741D03*
X244482Y1207777D03*
Y1199741D03*
X247482D03*
Y1207777D03*
X254978Y1199741D03*
Y1207777D03*
X247482Y1215296D03*
X254978D03*
X245878Y1670386D03*
X245707Y1692383D03*
X245878Y1684465D03*
Y1677870D03*
X245707Y1715381D03*
Y1707862D03*
Y1699826D03*
X259991Y2083607D03*
X275219Y3002D03*
X276523Y147585D03*
X271943Y147630D03*
X271547Y260353D03*
X276617Y256400D03*
X281193Y256624D03*
X285513Y322688D03*
X281074D03*
X289895D03*
X281569Y436169D03*
X286665Y432844D03*
X291002D03*
X274991Y463099D03*
X277776Y497341D03*
X273405D03*
X268938D03*
X285348Y610540D03*
X290984Y607215D03*
X276044Y624627D03*
X279044D03*
X274514Y672192D03*
X270109D03*
X283340D03*
X278955D03*
X273114Y785968D03*
X278184Y782643D03*
X282737D03*
X270070Y812192D03*
X268686Y847488D03*
X277788Y847237D03*
X273305D03*
X285966Y959767D03*
X291194Y956442D03*
X285666Y1016162D03*
X281124D03*
X290107D03*
X282958Y1134471D03*
X288188Y1131146D03*
X276807Y1191777D03*
X272082D03*
X283808Y1308959D03*
X289210Y1305634D03*
X284240Y1374544D03*
X279518Y1374543D03*
X275052Y1374715D03*
X270579Y1374626D03*
X275521Y1479435D03*
X279990D03*
X270234Y1482760D03*
X291054Y1543211D03*
X284086Y1659883D03*
X289421Y1656558D03*
X279703Y1723398D03*
X284583Y1723465D03*
X289499Y1723735D03*
X274704Y1723196D03*
X281066Y1834569D03*
X291550Y1829846D03*
X286623Y1829400D03*
X280240Y1858668D03*
X279976Y1864565D03*
X287121Y1898327D03*
X282717D03*
X278262D03*
X273817D03*
X299687Y78778D03*
X304151D03*
X308651D03*
X313089D03*
X294483Y82732D03*
X314914Y238162D03*
X294506Y322688D03*
X295509Y607215D03*
X295874Y956442D03*
X294617Y1016162D03*
X292698Y1131146D03*
X294133Y1305634D03*
X314183Y1403423D03*
X313894Y1513883D03*
X302267Y1524401D03*
X301734Y1513883D03*
X304870Y1543211D03*
X300392D03*
X295675D03*
X294090Y1656558D03*
X293606Y1858668D03*
X314562Y2009087D03*
X309991Y2083607D03*
X325219Y3002D03*
X322005Y78778D03*
X317567D03*
X320372Y225979D03*
X318088Y231820D03*
X321899Y238137D03*
X331046Y232021D03*
X324709Y231580D03*
X336617Y577978D03*
X329636Y584715D03*
X337387Y586230D03*
X331867Y589810D03*
X333750Y595326D03*
X329938Y948756D03*
X332527Y943746D03*
X318557Y941178D03*
X323868Y929978D03*
X336160Y937262D03*
X337509Y1109598D03*
X328989Y1121090D03*
X326558Y1126368D03*
X325796Y1162266D03*
X325636Y1399114D03*
X323813Y1753231D03*
X329887Y1752081D03*
X324803Y2005272D03*
X320045Y2005215D03*
X359931Y52189D03*
X361799Y311938D03*
X363825Y401768D03*
X342900Y580126D03*
X354000Y652170D03*
X356559Y675167D03*
X362577Y752783D03*
X343656Y933725D03*
X344099Y1106798D03*
X363169Y1329686D03*
X351391D03*
X354391D03*
X363169Y1350706D03*
Y1360043D03*
Y1340201D03*
X351391Y1350706D03*
Y1360043D03*
Y1340201D03*
X354391D03*
Y1360043D03*
Y1350706D03*
X363169Y1376210D03*
Y1367771D03*
X351391Y1376210D03*
Y1367771D03*
X354391D03*
Y1376210D03*
X350690Y1403243D03*
X348710Y1570187D03*
X361011Y1568890D03*
X343402Y1572080D03*
X348245Y1575241D03*
X355364Y1570990D03*
X352337Y1887285D03*
X363361Y1918313D03*
X358318Y1920680D03*
X363411Y1923459D03*
X359991Y2083607D03*
X375219Y3002D03*
X372204Y56126D03*
X379257Y52158D03*
X387524Y76847D03*
X374442Y406857D03*
X374542Y401282D03*
X368907Y404308D03*
X376654Y754748D03*
X382892Y767710D03*
X386790Y774338D03*
X379335Y1189778D03*
X383276Y1184136D03*
X386816Y1179841D03*
X376472Y1194999D03*
X373674Y1199967D03*
X371523Y1204725D03*
X366169Y1329686D03*
Y1340201D03*
Y1360043D03*
Y1350706D03*
X373564Y1352548D03*
X366169Y1367771D03*
Y1376210D03*
X367829Y1566108D03*
X366306Y1899864D03*
X374431Y1901397D03*
X374775Y1919243D03*
X379403Y1917261D03*
X369748Y1921795D03*
X402512Y17108D03*
Y67108D03*
Y117108D03*
Y167108D03*
Y217108D03*
Y267108D03*
Y317108D03*
Y367108D03*
Y417108D03*
Y467108D03*
Y517108D03*
Y567108D03*
Y617108D03*
Y667108D03*
Y717108D03*
Y767108D03*
Y817108D03*
Y867108D03*
Y917108D03*
Y967108D03*
Y1017108D03*
Y1067108D03*
Y1117108D03*
Y1167108D03*
Y1217108D03*
Y1267108D03*
Y1317108D03*
Y1367108D03*
Y1417108D03*
Y1467108D03*
Y1517108D03*
Y1567108D03*
Y1617108D03*
Y1667108D03*
Y1717108D03*
Y1767108D03*
Y1817108D03*
Y1867108D03*
Y1917108D03*
Y1967108D03*
Y2017108D03*
Y2067108D03*
G54D20*
G01X64979Y264500D02*
Y262811D01*
X56947Y254779D01*
X52570D01*
X41686Y265663D01*
Y288027D01*
X36876Y292837D01*
Y354660D01*
X31582Y359954D01*
X23837D01*
X14900Y368891D01*
Y442174D01*
X28619Y455893D01*
Y479422D01*
X62779Y513582D01*
X66266D01*
X76966Y524282D01*
Y628721D01*
X44211Y661476D01*
X39802Y665886D01*
Y740148D01*
X34104Y745846D01*
X31701D01*
X27951Y749596D01*
X24449D01*
X16540Y757505D01*
X14796D01*
X11497Y760804D01*
Y764162D01*
X12141Y764806D01*
Y768034D01*
X11083Y769092D01*
Y771622D01*
X11965Y772504D01*
Y776084D01*
X11137Y776912D01*
Y779550D01*
X11855Y780268D01*
Y784068D01*
X11247Y784676D01*
Y787534D01*
X11965Y788252D01*
Y791832D01*
X11497Y792300D01*
Y794091D01*
X7673Y797915D01*
G01X64979Y254500D02*
X68548Y258069D01*
Y266010D01*
X66061Y268497D01*
X63428D01*
X58893Y263962D01*
X49531D01*
X43391Y270102D01*
Y288734D01*
X38581Y293544D01*
Y355367D01*
X32289Y361659D01*
X23972D01*
X16200Y369431D01*
Y441204D01*
X29919Y454923D01*
Y478883D01*
X63318Y512282D01*
X66946D01*
X78366Y523702D01*
Y629160D01*
X45346Y662180D01*
X41407Y666120D01*
Y743833D01*
X37789Y747451D01*
X32366D01*
X28616Y751201D01*
X24906D01*
X16997Y759110D01*
X15030D01*
X12797Y761343D01*
Y763623D01*
X13441Y764267D01*
Y768573D01*
X12573Y769441D01*
Y771273D01*
X13401Y772101D01*
Y776487D01*
X12797Y777091D01*
Y779371D01*
X13291Y779865D01*
Y784471D01*
X12797Y784965D01*
Y787245D01*
X13318Y787766D01*
Y792318D01*
X12797Y792839D01*
Y806977D01*
X15547Y809727D01*
G01X7673Y805790D02*
Y804523D01*
X4923Y801773D01*
Y796775D01*
X10423Y791275D01*
Y788549D01*
X9839Y787965D01*
Y784245D01*
X10423Y783661D01*
Y780675D01*
X9701Y779953D01*
Y776509D01*
X10640Y775570D01*
Y773018D01*
X9783Y772161D01*
Y768553D01*
X10837Y767499D01*
Y765341D01*
X10197Y764701D01*
Y760265D01*
X11910Y758552D01*
Y752678D01*
X14760Y749828D01*
X17936D01*
X24623Y743141D01*
X27320D01*
X31333Y739128D01*
X36594D01*
X38402Y737320D01*
Y665447D01*
X43221Y660627D01*
X75664Y628184D01*
Y524821D01*
X65725Y514882D01*
X62240D01*
X27319Y479961D01*
Y456573D01*
X13600Y442854D01*
Y368352D01*
X23298Y358654D01*
X31040D01*
X35574Y354120D01*
Y292297D01*
X40386Y287485D01*
Y264093D01*
X54979Y249500D01*
G01Y269500D02*
X46292Y278187D01*
Y289936D01*
X41482Y294746D01*
Y356569D01*
X33491Y364560D01*
X25023D01*
X18900Y370683D01*
Y439801D01*
X32519Y453420D01*
Y477805D01*
X64396Y509682D01*
X68386D01*
X81572Y522868D01*
Y629634D01*
X44308Y666898D01*
Y749586D01*
X38239Y755655D01*
X31725D01*
X28220Y759160D01*
X23582D01*
X19867Y762875D01*
Y809914D01*
X16117Y813664D01*
X7673D01*
G01X64979Y244500D02*
X70230Y249751D01*
Y267400D01*
X67560Y270070D01*
X62295D01*
X57760Y265535D01*
X51176D01*
X44892Y271819D01*
Y289356D01*
X40082Y294166D01*
Y355989D01*
X32911Y363160D01*
X24443D01*
X17500Y370103D01*
Y440381D01*
X31219Y454100D01*
Y478344D01*
X63857Y510982D01*
X67706D01*
X80172Y523448D01*
Y629193D01*
X46408Y662959D01*
X42908Y666459D01*
Y749006D01*
X37659Y754255D01*
X31145D01*
X27640Y757760D01*
X23002D01*
X18551Y762211D01*
Y798849D01*
X15547Y801853D01*
G01X64979Y274500D02*
X51938D01*
X47692Y278746D01*
Y290516D01*
X42882Y295326D01*
Y357149D01*
X34071Y365960D01*
X25603D01*
X20300Y371263D01*
Y439221D01*
X33819Y452740D01*
Y477266D01*
X64935Y508382D01*
X69427D01*
X82972Y521927D01*
Y630073D01*
X45708Y667337D01*
Y752620D01*
X36357Y761971D01*
X31620D01*
X28167Y765424D01*
X24120D01*
X21196Y768348D01*
Y811952D01*
X15547Y817601D01*
G01X54979Y279500D02*
X49092Y285387D01*
Y291096D01*
X44282Y295906D01*
Y357729D01*
X39703Y362308D01*
Y445278D01*
X35119Y449862D01*
Y476727D01*
X65474Y507082D01*
X69966D01*
X84372Y521488D01*
Y630513D01*
X47108Y667777D01*
Y753200D01*
X36937Y763371D01*
X32200D01*
X28747Y766824D01*
X24700D01*
X22596Y768928D01*
Y815488D01*
X16546Y821538D01*
X7673D01*
G01X318088Y231820D02*
X306246Y243662D01*
X302814D01*
X202108Y344368D01*
X98124D01*
X76284Y366208D01*
Y435414D01*
X98773Y457903D01*
Y643654D01*
X58035Y684392D01*
Y780273D01*
X38579Y799729D01*
Y862210D01*
X35515Y865274D01*
X31467D01*
X27173Y869568D01*
X18698D01*
X15547Y872719D01*
G01X7673Y868782D02*
X16076D01*
X16590Y868268D01*
X26164D01*
X30458Y863974D01*
X34118D01*
X37231Y860861D01*
Y798332D01*
X56625Y778938D01*
Y683963D01*
X97381Y643207D01*
Y458801D01*
X74307Y435727D01*
Y366190D01*
X97539Y342958D01*
X200909D01*
X317888Y225979D01*
X320372D01*
G01X324709Y231580D02*
X309468Y246821D01*
X307277D01*
X303741Y250357D01*
Y252548D01*
X209196Y347093D01*
X100650D01*
X79608Y368135D01*
Y433349D01*
X101511Y455252D01*
Y644594D01*
X64090Y682015D01*
Y779338D01*
X41273Y802155D01*
Y870813D01*
X38966Y873120D01*
X32465D01*
X28437Y877148D01*
X18992D01*
X15547Y880593D01*
G01X7673Y876656D02*
X7684Y876645D01*
X17382D01*
X18270Y875757D01*
X27860D01*
X31888Y871729D01*
X38389D01*
X39881Y870237D01*
Y800987D01*
X59591Y781277D01*
Y684675D01*
X100166Y644100D01*
Y456602D01*
X78081Y434517D01*
Y367247D01*
X99583Y345745D01*
X204142D01*
X304751Y245136D01*
X307940D01*
X314914Y238162D01*
G01X372204Y56126D02*
X396449Y80371D01*
Y204813D01*
X375580Y225682D01*
X353062D01*
X311110Y267634D01*
X303320D01*
X215239Y355715D01*
X105448D01*
X88710Y372453D01*
Y427570D01*
X109663Y448523D01*
Y647505D01*
X74241Y682927D01*
Y780713D01*
X90851Y797323D01*
Y837547D01*
X59503Y868895D01*
Y872628D01*
X36839Y895292D01*
X30954D01*
X27095Y899151D01*
X24916D01*
X22356Y901711D01*
Y905800D01*
X24708Y908152D01*
X33263D01*
G01X321899Y238137D02*
X211643Y348393D01*
X101444D01*
X81224Y368613D01*
Y432450D01*
X102859Y454085D01*
Y645085D01*
X65525Y682419D01*
Y780194D01*
X42620Y803099D01*
Y875447D01*
X37943Y880124D01*
X30645D01*
X27015Y883754D01*
X16323D01*
X7673Y892404D01*
G01X331046Y232021D02*
X213327Y349740D01*
X102637D01*
X82751Y369626D01*
Y430924D01*
X104297Y452470D01*
Y645487D01*
X69041Y680743D01*
Y779102D01*
X43967Y804176D01*
Y876005D01*
X38501Y881471D01*
X31203D01*
X27573Y885101D01*
X18913D01*
X15547Y888467D01*
G01X329636Y584715D02*
Y593631D01*
X234000Y689267D01*
X108543D01*
X81009Y716801D01*
Y780502D01*
X95395Y794888D01*
Y852286D01*
X79700Y867981D01*
Y914870D01*
X75533Y919037D01*
X31958D01*
X27591Y923404D01*
X23083D01*
X18650Y927837D01*
X15547D01*
G01X331867Y589810D02*
Y593243D01*
X234496Y690614D01*
X109035D01*
X83614Y716035D01*
Y780692D01*
X96742Y793820D01*
Y852844D01*
X81750Y867836D01*
Y914725D01*
X76091Y920384D01*
X32789D01*
X28422Y924751D01*
X23641D01*
X16618Y931774D01*
X7673D01*
G01X336616Y577978D02*
X335551Y579043D01*
Y596525D01*
X334608Y597468D01*
X331320D01*
X235311Y693477D01*
X109852D01*
X88152Y715177D01*
Y781358D01*
X99807Y793013D01*
Y854099D01*
X84350Y869556D01*
Y916737D01*
X72357Y928730D01*
X31640D01*
X27652Y932718D01*
X24245D01*
X18093Y938870D01*
X14672D01*
X13905Y939637D01*
X7684D01*
X7673Y939648D01*
G01Y947522D02*
X7684Y947511D01*
X16781D01*
X18459Y945833D01*
Y944113D01*
X23463Y939109D01*
X27056D01*
X30874Y935291D01*
X72981D01*
X78974Y929298D01*
Y923975D01*
X85650Y917299D01*
Y871128D01*
X101319Y855459D01*
Y792265D01*
X89564Y780510D01*
Y715604D01*
X109977Y695191D01*
X235437D01*
X331485Y599143D01*
X335343D01*
X337387Y597099D01*
Y586230D01*
G01X333750Y595326D02*
X332964Y596112D01*
X330837D01*
X234906Y692043D01*
X109446D01*
X86523Y714966D01*
Y781692D01*
X98471Y793640D01*
Y853219D01*
X83050Y868640D01*
Y915789D01*
X71437Y927402D01*
X31005D01*
X27017Y931390D01*
X23694D01*
X19384Y935700D01*
X15558D01*
X15547Y935711D01*
G01X342900Y580126D02*
X339151Y583875D01*
Y597211D01*
X335812Y600550D01*
X331918D01*
X235840Y696628D01*
X110380D01*
X90899Y716109D01*
Y779968D01*
X102756Y791825D01*
Y856055D01*
X86950Y871861D01*
Y918032D01*
X80411Y924571D01*
Y929894D01*
X73577Y936728D01*
X31423D01*
X27605Y940546D01*
X24059D01*
X20200Y944405D01*
Y946806D01*
X15547Y951459D01*
G01X318557Y941178D02*
Y959028D01*
X251977Y1025608D01*
X190374D01*
X187632Y1028350D01*
X67181D01*
X43347Y1004516D01*
Y997621D01*
X35617Y989891D01*
X31069D01*
X26828Y994132D01*
X22090D01*
X19301Y996921D01*
Y999461D01*
X16122Y1002640D01*
X7673D01*
G01X323868Y929978D02*
Y942694D01*
X326014Y944840D01*
Y953410D01*
X252344Y1027080D01*
X191016D01*
X188369Y1029727D01*
X66388D01*
X41894Y1005233D01*
Y998232D01*
X35012Y991350D01*
X31674D01*
X27433Y995591D01*
X22695D01*
X20760Y997526D01*
Y1001364D01*
X15547Y1006577D01*
G01X329938Y948756D02*
Y951325D01*
X244427Y1036836D01*
X71540D01*
X39799Y1005095D01*
Y1002078D01*
X35672Y997951D01*
X30934D01*
X26559Y1002326D01*
X22186D01*
X20485Y1004027D01*
Y1005941D01*
X15912Y1010514D01*
X7673D01*
G01X332527Y943746D02*
Y950575D01*
X244964Y1038138D01*
X71000D01*
X37965Y1005103D01*
Y1002268D01*
X35079Y999382D01*
X31527D01*
X27246Y1003663D01*
X22873D01*
X21916Y1004620D01*
Y1008082D01*
X15547Y1014451D01*
G01X336160Y937262D02*
X334550Y938872D01*
Y950392D01*
X245366Y1039576D01*
X69852D01*
X36521Y1006245D01*
X30535D01*
X26714Y1010066D01*
X23007D01*
X19028Y1014045D01*
Y1018844D01*
X15547Y1022325D01*
G01X7673Y1026262D02*
X16101D01*
X20447Y1021916D01*
Y1014633D01*
X23595Y1011485D01*
X27302D01*
X31109Y1007678D01*
X35921D01*
X69256Y1041013D01*
X245771D01*
X335921Y950861D01*
Y941460D01*
X343656Y933725D01*
G01X379335Y1189778D02*
Y1151902D01*
X392876Y1138361D01*
Y1077843D01*
X371999Y1056966D01*
X291446D01*
X287858Y1053378D01*
X72592D01*
X37478Y1088492D01*
X31022D01*
X27340Y1092174D01*
X23834D01*
X19799Y1096209D01*
Y1097547D01*
X16284Y1101062D01*
X7677D01*
G01X376472Y1194999D02*
Y1152926D01*
X391576Y1137822D01*
Y1078382D01*
X371687Y1058493D01*
X286089D01*
X282604Y1055008D01*
X73268D01*
X38448Y1089828D01*
X31576D01*
X27894Y1093510D01*
X24388D01*
X21135Y1096763D01*
Y1099415D01*
X15551Y1104999D01*
G01Y1097125D02*
X20565Y1092111D01*
Y1089527D01*
X24178Y1085914D01*
X27683D01*
X31721Y1081876D01*
X42143D01*
X45984Y1078046D01*
X72020Y1052010D01*
X299626D01*
X302814Y1055198D01*
X372559D01*
X394176Y1076815D01*
Y1139389D01*
X381101Y1152464D01*
Y1181961D01*
X383276Y1184136D01*
G01X7677Y1093188D02*
X16096D01*
X19265Y1090019D01*
Y1088988D01*
X23639Y1084614D01*
X27144D01*
X31520Y1080238D01*
X41579D01*
X71111Y1050706D01*
X318213D01*
X319279Y1049640D01*
X327139D01*
X328205Y1050706D01*
X370227D01*
X395476Y1075955D01*
Y1140249D01*
X386816Y1148909D01*
Y1179841D01*
G01X25393Y1128622D02*
X21175Y1124404D01*
Y1119594D01*
X23391Y1117378D01*
X28550D01*
X31182Y1120010D01*
X87757D01*
X111407Y1143660D01*
Y1375810D01*
X118544Y1382947D01*
X170421D01*
X180114Y1373254D01*
X242231D01*
X317281Y1298204D01*
Y1273664D01*
X328731Y1262214D01*
Y1238843D01*
X361069Y1206505D01*
Y1173889D01*
X334080Y1146900D01*
Y1113027D01*
X337509Y1109598D01*
G01X373674Y1199967D02*
Y1153462D01*
X390276Y1136860D01*
Y1078944D01*
X371919Y1060587D01*
X285383D01*
X281172Y1056376D01*
X73835D01*
X40718Y1089493D01*
Y1092482D01*
X36725Y1096475D01*
X31154D01*
X27380Y1100249D01*
Y1100253D01*
X27026Y1100607D01*
X23045D01*
X18692Y1104960D01*
Y1106946D01*
X16743Y1108895D01*
X15592D01*
X7677Y1116810D01*
G01X15551Y1112873D02*
X20292Y1108132D01*
Y1105623D01*
X23708Y1102207D01*
X27267D01*
X31695Y1097779D01*
X37589D01*
X42514Y1092854D01*
Y1089865D01*
X74470Y1057909D01*
X279319D01*
X283909Y1062499D01*
X371992D01*
X388976Y1079483D01*
Y1135740D01*
X371523Y1153193D01*
Y1204725D01*
G01X348710Y1570187D02*
X391536Y1527361D01*
Y1411153D01*
X374018Y1393635D01*
X114483D01*
X98333Y1377485D01*
Y1155376D01*
X84606Y1141649D01*
X53251D01*
X35530Y1159370D01*
X30036D01*
X26220Y1163186D01*
X15485D01*
X11811Y1166860D01*
Y1167766D01*
X10620Y1168957D01*
Y1168986D01*
X7677Y1171929D01*
G01X15551Y1152244D02*
X18960Y1148835D01*
X27946D01*
X32010Y1144771D01*
X36898D01*
X48986Y1132683D01*
X91529D01*
X105905Y1147059D01*
Y1378310D01*
X116718Y1389123D01*
X376023D01*
X396143Y1409243D01*
Y1533758D01*
X361011Y1568890D01*
G01X15551Y1175866D02*
Y1173703D01*
X24726Y1164528D01*
X27706D01*
X31183Y1161051D01*
X35989D01*
X53261Y1143779D01*
X84545D01*
X94403Y1153637D01*
Y1375501D01*
X114091Y1395189D01*
X373508D01*
X390077Y1411758D01*
Y1525405D01*
X343402Y1572080D01*
G01X348245Y1575241D02*
X393126Y1530360D01*
Y1410494D01*
X374772Y1392140D01*
X115916D01*
X102888Y1379112D01*
Y1153489D01*
X87786Y1138387D01*
X50461D01*
X35580Y1153268D01*
X31960D01*
X28686Y1156542D01*
X19127D01*
X15551Y1160118D01*
G01X7677Y1164055D02*
X16735Y1154997D01*
X28356D01*
X31391Y1151962D01*
X34729D01*
X49664Y1137027D01*
X88350D01*
X104248Y1152925D01*
Y1378631D01*
X116397Y1390780D01*
X375336D01*
X394486Y1409930D01*
Y1531868D01*
X355364Y1570990D01*
G01X7677Y1156180D02*
X16391Y1147466D01*
X27347D01*
X31433Y1143380D01*
X36070D01*
X48303Y1131147D01*
X91961D01*
X107296Y1146482D01*
Y1377681D01*
X117347Y1387732D01*
X376600D01*
X397534Y1408666D01*
Y1536403D01*
X367829Y1566108D01*
G01X374775Y1919243D02*
X393372Y1900646D01*
Y1781787D01*
X353958Y1742373D01*
X184729D01*
X172209Y1729853D01*
X121317D01*
X113908Y1722444D01*
Y1492658D01*
X85133Y1463883D01*
Y1381292D01*
X83574Y1379733D01*
Y1246647D01*
X52999Y1216072D01*
X28502D01*
X26388Y1218186D01*
X14564D01*
X7677Y1211299D01*
G01X379403Y1917261D02*
X394827Y1901837D01*
Y1780881D01*
X355019Y1741073D01*
X185314D01*
X172794Y1728553D01*
X122050D01*
X115269Y1721772D01*
Y1487378D01*
X86433Y1458542D01*
Y1380753D01*
X84874Y1379194D01*
Y1245913D01*
X53199Y1214238D01*
X31720D01*
X28638Y1211156D01*
X19631D01*
X15551Y1215236D01*
G01X363361Y1918313D02*
X368767D01*
X389214Y1897866D01*
Y1784479D01*
X351422Y1746687D01*
X179402D01*
X175126Y1742411D01*
X126504D01*
X109699Y1725606D01*
Y1495728D01*
X81233Y1467262D01*
Y1382909D01*
X79674Y1381350D01*
Y1254436D01*
X55651Y1230413D01*
X31140D01*
X27408Y1234145D01*
X18712D01*
X15551Y1230984D01*
G01X358318Y1920680D02*
X363646Y1915352D01*
X369790D01*
X387869Y1897273D01*
Y1784973D01*
X351067Y1748171D01*
X178021D01*
X173729Y1743879D01*
X125304D01*
X108083Y1726658D01*
Y1496780D01*
X79639Y1468336D01*
Y1383154D01*
X78374Y1381889D01*
Y1261569D01*
X48581Y1231776D01*
X32101D01*
X28039Y1235838D01*
X8594D01*
X7677Y1234921D01*
G01X363411Y1923459D02*
X365606D01*
X390606Y1898459D01*
Y1783620D01*
X352336Y1745350D01*
X180881D01*
X176610Y1741079D01*
X127712D01*
X111079Y1724446D01*
Y1494568D01*
X82533Y1466022D01*
Y1382370D01*
X80974Y1380811D01*
Y1252933D01*
X51832Y1223791D01*
X31947D01*
X28022Y1227716D01*
X20157D01*
X15551Y1223110D01*
G01X369748Y1921795D02*
X392045Y1899498D01*
Y1782656D01*
X353335Y1743946D01*
X184340D01*
X171547Y1731153D01*
X120075D01*
X112471Y1723549D01*
Y1493671D01*
X83833Y1465033D01*
Y1381831D01*
X82274Y1380272D01*
Y1252153D01*
X52154Y1222033D01*
X31030D01*
X26914Y1226149D01*
X23327D01*
X17045Y1219867D01*
X8371D01*
X7677Y1219173D01*
G01X25389Y770357D02*
X34884D01*
X48408Y756833D01*
Y668316D01*
X87725Y628999D01*
Y522870D01*
X70637Y505782D01*
X66013D01*
X36419Y476188D01*
Y452134D01*
X41385Y447168D01*
Y371680D01*
X72003Y341062D01*
Y240522D01*
X71503Y240022D01*
X71206D01*
X45740Y214556D01*
Y193075D01*
X48726Y190089D01*
Y176046D01*
X53272Y171500D01*
X64979D01*
G01X25389Y778231D02*
X35101D01*
X51108Y762224D01*
Y669295D01*
X90525Y629878D01*
Y521298D01*
X72409Y503182D01*
X67091D01*
X39019Y475110D01*
Y453494D01*
X44185Y448328D01*
Y372840D01*
X74803Y342222D01*
Y239362D01*
X72663Y237222D01*
X72366D01*
X48540Y213396D01*
Y194235D01*
X51150Y191625D01*
X56048D01*
X64979Y182694D01*
Y181500D01*
G01X54979Y176500D02*
X50160Y181319D01*
Y190635D01*
X47140Y193655D01*
Y213976D01*
X71786Y238622D01*
X72083D01*
X73403Y239942D01*
Y341642D01*
X42785Y372260D01*
Y447748D01*
X37719Y452814D01*
Y475649D01*
X66552Y504482D01*
X71317D01*
X89125Y522290D01*
Y629438D01*
X49708Y668855D01*
Y757848D01*
X33263Y774293D01*
G01Y782167D02*
X52508Y762922D01*
Y669734D01*
X91925Y630317D01*
Y520458D01*
X73349Y501882D01*
X67630D01*
X40319Y474571D01*
Y454174D01*
X45585Y448908D01*
Y373420D01*
X76203Y342802D01*
Y238782D01*
X73243Y235822D01*
X72946D01*
X49906Y212782D01*
Y201573D01*
X54979Y196500D01*
G01Y206500D02*
X54620Y206859D01*
Y213536D01*
X74106Y233022D01*
X74403D01*
X79003Y237622D01*
Y343962D01*
X48385Y374580D01*
Y450068D01*
X42919Y455534D01*
Y473493D01*
X68708Y499282D01*
X74840D01*
X94725Y519167D01*
Y644023D01*
X55308Y683440D01*
Y767996D01*
X33263Y790041D01*
G01X25389Y786105D02*
X33411D01*
X53908Y765608D01*
Y682860D01*
X93325Y643443D01*
Y520019D01*
X73888Y500582D01*
X68169D01*
X41619Y474032D01*
Y454854D01*
X46985Y449488D01*
Y374000D01*
X77603Y343382D01*
Y238202D01*
X73823Y234422D01*
X73526D01*
X51296Y212192D01*
Y203840D01*
X53636Y201500D01*
X64979D01*
G01X48433Y866179D02*
X51423D01*
X86577Y831025D01*
Y800968D01*
X70341Y784732D01*
Y681283D01*
X105610Y646014D01*
Y450964D01*
X84114Y429468D01*
Y370986D01*
X104054Y351046D01*
X215504D01*
X302216Y264334D01*
X310732D01*
X352908Y222158D01*
X372166D01*
X392235Y202089D01*
Y84493D01*
X359931Y52189D01*
G01X387524Y76847D02*
X393668Y82991D01*
Y203002D01*
X372621Y224049D01*
X352856D01*
X311244Y265661D01*
X303170D01*
X216352Y352479D01*
X104836D01*
X85450Y371865D01*
Y428231D01*
X107011Y449792D01*
Y646452D01*
X71641Y681822D01*
Y783567D01*
X88070Y799996D01*
Y831683D01*
X50475Y869278D01*
X48467D01*
G01X33263Y900278D02*
X39171D01*
X62633Y876816D01*
X63249D01*
X93815Y846250D01*
Y795166D01*
X77182Y778533D01*
Y718789D01*
X112467Y683504D01*
Y447632D01*
X91473Y426638D01*
Y373489D01*
X105501Y359461D01*
X213332D01*
X303859Y268934D01*
X311649D01*
X353289Y227294D01*
X379266D01*
X399579Y206981D01*
Y72470D01*
X379257Y52148D01*
G01X374442Y406857D02*
X394138Y426553D01*
Y602811D01*
X362333Y634616D01*
X303369D01*
X236558Y701427D01*
X120909D01*
X103236Y719100D01*
Y751046D01*
X99061Y755221D01*
Y781561D01*
X106852Y789352D01*
Y859824D01*
X103945Y862731D01*
Y907195D01*
X85109Y926031D01*
Y933283D01*
X70881Y947511D01*
X33274D01*
X33263Y947522D01*
G01X363825Y401768D02*
X391004Y428947D01*
Y601966D01*
X361488Y631482D01*
X302825D01*
X236014Y698293D01*
X110554D01*
X92499Y716348D01*
Y779434D01*
X104113Y791048D01*
Y857053D01*
X94625Y866541D01*
Y912712D01*
X81975Y925362D01*
Y931984D01*
X71515Y942444D01*
X30479D01*
X29349Y943574D01*
X25400D01*
X25389Y943585D01*
G01X368907Y404308D02*
X392801Y428202D01*
Y602257D01*
X361779Y633279D01*
X302867D01*
X236056Y700090D01*
X116272D01*
X101852Y714510D01*
Y750590D01*
X97354Y755088D01*
Y781816D01*
X105505Y789967D01*
Y858203D01*
X96059Y867649D01*
Y913190D01*
X83772Y925477D01*
Y932729D01*
X72175Y944326D01*
X31620D01*
X29234Y946712D01*
Y955488D01*
X25389Y959333D01*
G01X374542Y401282D02*
X397078Y423818D01*
Y602021D01*
X362577Y636522D01*
X303303D01*
X235458Y704367D01*
X121811D01*
X109342Y716836D01*
Y755056D01*
X104776Y759622D01*
Y782837D01*
X109518Y787579D01*
Y861317D01*
X106645Y864190D01*
Y908784D01*
X88245Y927184D01*
Y934306D01*
X62731Y959820D01*
X32776D01*
X25389Y967207D01*
G01X33263Y1010514D02*
X65186Y1042437D01*
X246186D01*
X312370Y976253D01*
X367121D01*
X391691Y951683D01*
Y781897D01*
X362577Y752783D01*
G01X25389Y1014451D02*
X29579Y1018641D01*
Y1026740D01*
X47996Y1045157D01*
X247145D01*
X313449Y978853D01*
X369090D01*
X394415Y953528D01*
Y779233D01*
X382892Y767710D01*
G01X386790Y774338D02*
X393027Y780575D01*
Y952660D01*
X368134Y977553D01*
X312909D01*
X246689Y1043773D01*
X50774D01*
X33263Y1026262D01*
G01X25393Y1065629D02*
Y1061692D01*
X39060Y1048025D01*
X246116D01*
X313969Y980172D01*
X369610D01*
X398022Y951760D01*
Y776116D01*
X376654Y754748D01*
G01X328989Y1121090D02*
Y1147201D01*
X357257Y1175469D01*
Y1208362D01*
X320155Y1245464D01*
Y1266792D01*
X314455Y1272492D01*
Y1297032D01*
X239688Y1371799D01*
X179033D01*
X170711Y1380121D01*
X119806D01*
X114233Y1374548D01*
Y1142230D01*
X88836Y1116834D01*
X41165D01*
X33267Y1108936D01*
G01X326558Y1126368D02*
Y1146998D01*
X355682Y1176122D01*
Y1207709D01*
X318580Y1244811D01*
Y1266139D01*
X312880Y1271839D01*
Y1296379D01*
X238853Y1370406D01*
X178154D01*
X170014Y1378546D01*
X120144D01*
X115808Y1374210D01*
Y1141735D01*
X89399Y1115326D01*
X43730D01*
X33403Y1104999D01*
X25393D01*
G01Y1120748D02*
X28922D01*
X29550Y1121376D01*
X86659D01*
X110060Y1144777D01*
Y1376368D01*
X117986Y1384294D01*
X171431D01*
X181100Y1374625D01*
X242765D01*
X318628Y1298762D01*
Y1274222D01*
X330078Y1262772D01*
Y1239401D01*
X362416Y1207063D01*
Y1173331D01*
X335380Y1146295D01*
Y1115517D01*
X344099Y1106798D01*
G01X33267Y1164055D02*
X41642Y1172430D01*
Y1176080D01*
X52887Y1187325D01*
Y1193647D01*
X92811Y1233571D01*
Y1375855D01*
X115843Y1398887D01*
X154924D01*
X158563Y1402526D01*
X164370D01*
X170224Y1396672D01*
X344155D01*
X350690Y1403207D01*
G01X314183Y1403423D02*
X179796D01*
X174504Y1408715D01*
X157763D01*
X152471Y1403423D01*
X111181D01*
X90383Y1382625D01*
Y1379186D01*
X88774Y1377577D01*
Y1239252D01*
X50607Y1201085D01*
X50606D01*
X45250Y1195729D01*
Y1191786D01*
X33267Y1179803D01*
G01X325636Y1399114D02*
X176594D01*
X170951Y1404757D01*
X158226D01*
X153793Y1400324D01*
X115199D01*
X91374Y1376499D01*
Y1234503D01*
X51212Y1194341D01*
Y1189133D01*
X38978Y1176899D01*
Y1172745D01*
X34225Y1167992D01*
X25393D01*
G01X33267Y1187677D02*
X39284Y1193694D01*
Y1194212D01*
X86174Y1241102D01*
Y1378655D01*
X87733Y1380214D01*
Y1386605D01*
X96510Y1395382D01*
G01X329887Y1752081D02*
X327277Y1749471D01*
X175456D01*
X171700Y1745715D01*
X122925D01*
X105103Y1727893D01*
Y1498015D01*
X64940Y1457852D01*
Y1269960D01*
X43374Y1248394D01*
Y1247366D01*
X34866Y1238858D01*
X25393D01*
G01Y1246732D02*
X35943D01*
X56293Y1267082D01*
Y1302917D01*
X58893Y1305517D01*
Y1310798D01*
X58013Y1311678D01*
Y1455222D01*
X102065Y1499274D01*
Y1729152D01*
X120010Y1747097D01*
X168329D01*
X172003Y1750771D01*
X321353D01*
X323813Y1753231D01*
G01X94347Y421562D02*
X105433Y410476D01*
X123681D01*
X128055Y406102D01*
X139920D01*
G01X347165Y1434705D02*
X341916D01*
X332772Y1425561D01*
Y1422505D01*
X316695Y1406428D01*
X180078D01*
X174086Y1412420D01*
X156122D01*
X149773Y1406071D01*
X107199D01*
X96510Y1395382D01*
G01X356559Y675167D02*
Y683167D01*
X332593Y707133D01*
X123542D01*
X119920Y710755D01*
Y714134D01*
G01X366306Y1899864D02*
X369633D01*
X381769Y1887728D01*
Y1802973D01*
X374033Y1795237D01*
X334772D01*
X327661Y1788126D01*
Y1767838D01*
X317278Y1757455D01*
X162829D01*
X159179Y1753805D01*
X124343D01*
X119920Y1758228D01*
G01X347165Y1424705D02*
X346046Y1423586D01*
Y1417194D01*
X339433Y1410581D01*
X334141D01*
X326983Y1403423D01*
X314183D01*
G01X337165Y34705D02*
X346261Y43801D01*
X351543D01*
X359931Y52189D01*
G01X362165Y194705D02*
X361979D01*
X358299Y191025D01*
X339486D01*
X331476Y199035D01*
Y218432D01*
X318088Y231820D01*
G01X320372Y225979D02*
X329742Y216609D01*
Y198221D01*
X338499Y189464D01*
X363804D01*
X367008Y192668D01*
Y197762D01*
X365065Y199705D01*
X357165D01*
G01X314914Y238162D02*
X333694Y219382D01*
Y203176D01*
X337165Y199705D01*
G01X321899Y238137D02*
X338120Y221916D01*
X339856D01*
X355737Y206035D01*
X360835D01*
X362165Y204705D01*
G01X357165Y209705D02*
X343347Y223523D01*
X339544D01*
X331046Y232021D01*
G01X324709Y231580D02*
X340704Y215585D01*
Y208018D01*
X338911Y206225D01*
Y202774D01*
X342165Y199520D01*
Y194705D01*
G01X363825Y401768D02*
X361967Y399910D01*
X348434D01*
X337165Y388641D01*
Y384705D01*
G01X347165Y374705D02*
X347146Y374686D01*
X342158D01*
X338454Y378390D01*
Y381195D01*
X340810Y383551D01*
Y388842D01*
X349163Y397195D01*
X361794D01*
X368907Y404308D01*
G01X336616Y577978D02*
X341625Y572969D01*
Y558724D01*
X338758Y555857D01*
Y553186D01*
X342166Y549778D01*
Y544705D01*
G01X357166Y549705D02*
X358644Y548227D01*
X364036D01*
X365498Y546765D01*
Y543217D01*
X361636Y539355D01*
X338618D01*
X329636Y548337D01*
Y584715D01*
G01X362166Y544705D02*
X358163Y540702D01*
X340092D01*
X331867Y548927D01*
Y589810D01*
G01X333750Y595326D02*
Y553121D01*
X337166Y549705D01*
G01X336616Y577978D02*
X336617D01*
G01X337387Y586230D02*
Y582144D01*
X357166Y562365D01*
Y559705D01*
G01X347166Y724705D02*
X347098Y724773D01*
X341864D01*
X338692Y727945D01*
Y731766D01*
X340640Y733714D01*
Y737744D01*
X351018Y748122D01*
X360574D01*
X386790Y774338D01*
G01X362577Y752783D02*
X359807Y750013D01*
X349175D01*
X337166Y738004D01*
Y734705D01*
G01X329938Y948756D02*
Y938026D01*
X326730Y934818D01*
Y928798D01*
X331163Y924365D01*
Y905707D01*
X337165Y899705D01*
G01X318557Y941178D02*
Y929169D01*
X326633Y921093D01*
Y902514D01*
X340041Y889106D01*
X361472D01*
X365636Y893270D01*
Y896725D01*
X364154Y898207D01*
X358663D01*
X357165Y899705D01*
G01X323868Y929978D02*
Y927737D01*
X328870Y922735D01*
Y902512D01*
X340696Y890686D01*
X358146D01*
X362165Y894705D01*
G01X332527Y943746D02*
Y936475D01*
X335741Y933261D01*
Y924251D01*
X333761Y922271D01*
Y907678D01*
X342165Y899274D01*
Y894705D01*
G01X357165Y909705D02*
Y916257D01*
X336160Y937262D01*
G01X337165Y1084705D02*
Y1100048D01*
X326558Y1110655D01*
Y1126368D01*
G01X328989Y1121090D02*
Y1111592D01*
X342165Y1098416D01*
Y1079705D01*
G01X337509Y1109598D02*
X347165Y1099942D01*
Y1084705D01*
G01X337165Y1249705D02*
X342013D01*
X379335Y1212383D01*
Y1189778D01*
G01X373674Y1199967D02*
Y1208486D01*
X334072Y1248088D01*
Y1260932D01*
X337170Y1264030D01*
X347898D01*
X355365Y1256563D01*
X360307D01*
X362165Y1254705D01*
G01X357165Y1259705D02*
X351540Y1265330D01*
X336520D01*
X332772Y1261582D01*
Y1246592D01*
X371523Y1207841D01*
Y1204725D01*
G01X325636Y1399114D02*
X328553D01*
X335303Y1405864D01*
X343604D01*
X360704Y1422964D01*
Y1426708D01*
X354590Y1432822D01*
X350311D01*
X348324Y1430835D01*
X345534D01*
X344404Y1429705D01*
X342165D01*
G01X350690Y1403207D02*
X365710Y1418227D01*
Y1431598D01*
X358067Y1439241D01*
X341701D01*
X337165Y1434705D01*
G01X362165Y1604705D02*
Y1609452D01*
X355275Y1616342D01*
X334832D01*
X330324Y1611834D01*
Y1585158D01*
X343402Y1572080D01*
G01X348710Y1570187D02*
X332697Y1586200D01*
Y1610851D01*
X335815Y1613969D01*
X352901D01*
X357165Y1609705D01*
G01X348245Y1575241D02*
X337165Y1586321D01*
Y1599705D01*
G01X323813Y1753231D02*
X336736Y1766154D01*
Y1769268D01*
X347165Y1779697D01*
Y1784705D01*
G01X329887Y1752081D02*
X347165Y1769359D01*
Y1774705D01*
G01X357165Y1959705D02*
X353396Y1963474D01*
X336515D01*
X333460Y1960419D01*
Y1948214D01*
X363361Y1918313D01*
G01X362165Y1954705D02*
Y1960038D01*
X356818Y1965385D01*
X336057D01*
X331854Y1961182D01*
Y1947144D01*
X358318Y1920680D01*
G01X369748Y1921795D02*
X341838Y1949705D01*
X337165D01*
G01X379257Y52148D02*
X351814Y24705D01*
X347165D01*
G01X342165Y29705D02*
Y36912D01*
X347411Y42158D01*
X352835D01*
X387524Y76847D01*
G01X372204Y56126D02*
X350783Y34705D01*
X347165D01*
G01X374442Y406857D02*
X362987Y395402D01*
X349235D01*
X342165Y388332D01*
Y379705D01*
G01X374542Y401282D02*
X365206Y391946D01*
X354406D01*
X347165Y384705D01*
G01X362166Y554705D02*
Y560860D01*
X342900Y580126D01*
G01X382892Y767710D02*
X361508Y746326D01*
X351743D01*
X342166Y736749D01*
Y729705D01*
G01X347166Y734705D02*
X355095Y742634D01*
X364540D01*
X376654Y754748D01*
G01X343656Y933725D02*
X362165Y915216D01*
Y904705D01*
G01X344099Y1106798D02*
X350539Y1100358D01*
Y1083109D01*
X347165Y1079735D01*
Y1074705D01*
G01X376472Y1194999D02*
Y1210410D01*
X345372Y1241498D01*
X342165Y1244705D01*
G01X362165D02*
X383276Y1223594D01*
Y1184136D01*
G01X357165Y1249705D02*
X363021D01*
X386816Y1225910D01*
Y1179841D01*
G01X350690Y1403243D02*
Y1403207D01*
G01X357165Y1599705D02*
Y1572736D01*
X361011Y1568890D01*
G01X342165Y1594705D02*
Y1584189D01*
X355364Y1570990D01*
G01X362165Y1594705D02*
Y1571772D01*
X367829Y1566108D01*
G01X374775Y1919243D02*
X357165Y1936853D01*
Y1949705D01*
G01X342165Y1944705D02*
X363411Y1923459D01*
G01X379403Y1917261D02*
X362165Y1934499D01*
Y1944705D01*
G01X379257Y52158D02*
Y52148D01*
G54D11*
X22756Y113818D03*
X22480Y316838D03*
Y340460D03*
X22756Y1866819D03*
Y1948818D03*
Y2023818D03*
G54D21*
G01X-723776Y2987387D02*
Y-376795D01*
Y-489221D01*
X1782976D01*
Y-376795D01*
Y2987387D01*
X-723776D01*
G01X-4000Y-62500D02*
Y-137500D01*
X496000D01*
Y-62500D01*
X-4000D01*
G01X8000Y-127500D02*
Y-132500D01*
G01X6543Y-127500D02*
X9457D01*
G01X14367Y-132500D02*
X11833D01*
Y-127500D01*
X14367D01*
G01X13353Y-129917D02*
X11833D01*
G01X16933Y-127500D02*
Y-132500D01*
X19467D01*
G01X23300Y-132667D02*
X23173Y-132583D01*
Y-132417D01*
X23300Y-132333D01*
X23427Y-132417D01*
Y-132583D01*
X23300Y-132667D01*
G01Y-130417D02*
X23173Y-130333D01*
Y-130167D01*
X23300Y-130083D01*
X23427Y-130167D01*
Y-130333D01*
X23300Y-130417D01*
G01X28083Y-134167D02*
X27450Y-133333D01*
X27133Y-132500D01*
Y-129167D01*
X27450Y-128333D01*
X28083Y-127500D01*
G01X33500D02*
X32993Y-127667D01*
X32613Y-128083D01*
X32360Y-128583D01*
X32170Y-129250D01*
X32107Y-130000D01*
X32170Y-130750D01*
X32360Y-131417D01*
X32613Y-131917D01*
X32993Y-132333D01*
X33500Y-132500D01*
X34007Y-132333D01*
X34387Y-131917D01*
X34640Y-131417D01*
X34830Y-130750D01*
X34893Y-130000D01*
X34830Y-129250D01*
X34640Y-128583D01*
X34387Y-128083D01*
X34007Y-127667D01*
X33500Y-127500D01*
G01X37207Y-131500D02*
X37587Y-132083D01*
X38093Y-132417D01*
X38663Y-132500D01*
X39170Y-132417D01*
X39677Y-132000D01*
X39993Y-131500D01*
X40057Y-131000D01*
X39930Y-130417D01*
X39487Y-130000D01*
X39043Y-129833D01*
X38473D01*
G01X39043D02*
X39423Y-129583D01*
X39740Y-129167D01*
X39867Y-128667D01*
X39740Y-128167D01*
X39423Y-127750D01*
X38853Y-127500D01*
X38283Y-127583D01*
X37713Y-127917D01*
G01X44017Y-134167D02*
X44650Y-133333D01*
X44967Y-132500D01*
Y-129167D01*
X44650Y-128333D01*
X44017Y-127500D01*
G01X47407Y-131500D02*
X47787Y-132083D01*
X48293Y-132417D01*
X48863Y-132500D01*
X49370Y-132417D01*
X49877Y-132000D01*
X50193Y-131500D01*
X50257Y-131000D01*
X50130Y-130417D01*
X49687Y-130000D01*
X49243Y-129833D01*
X48673D01*
G01X49243D02*
X49623Y-129583D01*
X49940Y-129167D01*
X50067Y-128667D01*
X49940Y-128167D01*
X49623Y-127750D01*
X49053Y-127500D01*
X48483Y-127583D01*
X47913Y-127917D01*
G01X52697Y-128333D02*
X53077Y-127833D01*
X53520Y-127583D01*
X54027Y-127500D01*
X54660Y-127667D01*
X55103Y-128083D01*
X55230Y-128583D01*
X55167Y-129083D01*
X54913Y-129500D01*
X53647Y-130333D01*
X53077Y-130917D01*
X52697Y-131750D01*
X52570Y-132500D01*
X55230D01*
G01X58873D02*
X59000Y-131417D01*
X59190Y-130500D01*
X59443Y-129667D01*
X59760Y-128750D01*
X60267Y-127500D01*
X57733D01*
G01X63277Y-130833D02*
X64923D01*
G01X67997Y-128333D02*
X68377Y-127833D01*
X68820Y-127583D01*
X69327Y-127500D01*
X69960Y-127667D01*
X70403Y-128083D01*
X70530Y-128583D01*
X70467Y-129083D01*
X70213Y-129500D01*
X68947Y-130333D01*
X68377Y-130917D01*
X67997Y-131750D01*
X67870Y-132500D01*
X70530D01*
G01X72907Y-131500D02*
X73287Y-132083D01*
X73793Y-132417D01*
X74363Y-132500D01*
X74870Y-132417D01*
X75377Y-132000D01*
X75693Y-131500D01*
X75757Y-131000D01*
X75630Y-130417D01*
X75187Y-130000D01*
X74743Y-129833D01*
X74173D01*
G01X74743D02*
X75123Y-129583D01*
X75440Y-129167D01*
X75567Y-128667D01*
X75440Y-128167D01*
X75123Y-127750D01*
X74553Y-127500D01*
X73983Y-127583D01*
X73413Y-127917D01*
G01X80160Y-132500D02*
Y-127500D01*
X77817Y-131083D01*
X80983D01*
G01X83107Y-131750D02*
X83487Y-132167D01*
X83930Y-132417D01*
X84500Y-132500D01*
X85070Y-132333D01*
X85513Y-132000D01*
X85830Y-131417D01*
X85893Y-130750D01*
X85767Y-130083D01*
X85450Y-129667D01*
X85007Y-129333D01*
X84563Y-129250D01*
X84120Y-129333D01*
X83550Y-129667D01*
X83740Y-127500D01*
X85450D01*
G01X93497Y-132500D02*
Y-127500D01*
X95903D01*
G01X95017Y-129917D02*
X93497D01*
G01X98217Y-132500D02*
X99800Y-127500D01*
X101383Y-132500D01*
G01X100813Y-130750D02*
X98787D01*
G01X103570Y-132500D02*
X106230Y-127500D01*
G01X103570D02*
X106230Y-132500D01*
G01X110000Y-132667D02*
X109873Y-132583D01*
Y-132417D01*
X110000Y-132333D01*
X110127Y-132417D01*
Y-132583D01*
X110000Y-132667D01*
G01Y-130417D02*
X109873Y-130333D01*
Y-130167D01*
X110000Y-130083D01*
X110127Y-130167D01*
Y-130333D01*
X110000Y-130417D01*
G01X114783Y-134167D02*
X114150Y-133333D01*
X113833Y-132500D01*
Y-129167D01*
X114150Y-128333D01*
X114783Y-127500D01*
G01X120200D02*
X119693Y-127667D01*
X119313Y-128083D01*
X119060Y-128583D01*
X118870Y-129250D01*
X118807Y-130000D01*
X118870Y-130750D01*
X119060Y-131417D01*
X119313Y-131917D01*
X119693Y-132333D01*
X120200Y-132500D01*
X120707Y-132333D01*
X121087Y-131917D01*
X121340Y-131417D01*
X121530Y-130750D01*
X121593Y-130000D01*
X121530Y-129250D01*
X121340Y-128583D01*
X121087Y-128083D01*
X120707Y-127667D01*
X120200Y-127500D01*
G01X123907Y-131500D02*
X124287Y-132083D01*
X124793Y-132417D01*
X125363Y-132500D01*
X125870Y-132417D01*
X126377Y-132000D01*
X126693Y-131500D01*
X126757Y-131000D01*
X126630Y-130417D01*
X126187Y-130000D01*
X125743Y-129833D01*
X125173D01*
G01X125743D02*
X126123Y-129583D01*
X126440Y-129167D01*
X126567Y-128667D01*
X126440Y-128167D01*
X126123Y-127750D01*
X125553Y-127500D01*
X124983Y-127583D01*
X124413Y-127917D01*
G01X130717Y-134167D02*
X131350Y-133333D01*
X131667Y-132500D01*
Y-129167D01*
X131350Y-128333D01*
X130717Y-127500D01*
G01X134107Y-131500D02*
X134487Y-132083D01*
X134993Y-132417D01*
X135563Y-132500D01*
X136070Y-132417D01*
X136577Y-132000D01*
X136893Y-131500D01*
X136957Y-131000D01*
X136830Y-130417D01*
X136387Y-130000D01*
X135943Y-129833D01*
X135373D01*
G01X135943D02*
X136323Y-129583D01*
X136640Y-129167D01*
X136767Y-128667D01*
X136640Y-128167D01*
X136323Y-127750D01*
X135753Y-127500D01*
X135183Y-127583D01*
X134613Y-127917D01*
G01X139523Y-131917D02*
X139967Y-132333D01*
X140473Y-132500D01*
X140980Y-132333D01*
X141423Y-131833D01*
X141740Y-131083D01*
X141867Y-130333D01*
Y-129417D01*
X141740Y-128667D01*
X141423Y-128000D01*
X141043Y-127667D01*
X140600Y-127500D01*
X140093Y-127667D01*
X139713Y-128000D01*
X139460Y-128500D01*
X139333Y-129167D01*
X139460Y-129750D01*
X139777Y-130333D01*
X140157Y-130667D01*
X140600Y-130750D01*
X141107Y-130583D01*
X141487Y-130167D01*
X141867Y-129417D01*
G01X145573Y-132500D02*
X145700Y-131417D01*
X145890Y-130500D01*
X146143Y-129667D01*
X146460Y-128750D01*
X146967Y-127500D01*
X144433D01*
G01X149977Y-130833D02*
X151623D01*
G01X154507Y-131500D02*
X154887Y-132083D01*
X155393Y-132417D01*
X155963Y-132500D01*
X156470Y-132417D01*
X156977Y-132000D01*
X157293Y-131500D01*
X157357Y-131000D01*
X157230Y-130417D01*
X156787Y-130000D01*
X156343Y-129833D01*
X155773D01*
G01X156343D02*
X156723Y-129583D01*
X157040Y-129167D01*
X157167Y-128667D01*
X157040Y-128167D01*
X156723Y-127750D01*
X156153Y-127500D01*
X155583Y-127583D01*
X155013Y-127917D01*
G01X159797Y-130417D02*
X160240Y-129833D01*
X160620Y-129500D01*
X161127Y-129333D01*
X161570Y-129500D01*
X161887Y-129833D01*
X162140Y-130333D01*
X162203Y-130917D01*
X162140Y-131417D01*
X161887Y-131917D01*
X161507Y-132333D01*
X161063Y-132500D01*
X160557Y-132333D01*
X160113Y-131833D01*
X159860Y-131083D01*
X159797Y-130250D01*
X159923Y-129167D01*
X160113Y-128583D01*
X160430Y-128000D01*
X160873Y-127583D01*
X161317Y-127500D01*
X161760Y-127667D01*
X162077Y-128083D01*
G01X166100Y-132500D02*
Y-127500D01*
X165340Y-128500D01*
G01Y-132500D02*
X166860D01*
G01X171960D02*
Y-127500D01*
X169617Y-131083D01*
X172783D01*
G01X191000Y-62500D02*
Y-137500D01*
G01Y-112500D02*
X294000D01*
Y-87500D01*
G01X191000D02*
X294000D01*
G01X301507Y-122500D02*
Y-117500D01*
X302773D01*
X303280Y-117750D01*
X303660Y-118083D01*
X303977Y-118583D01*
X304230Y-119167D01*
X304293Y-120000D01*
X304230Y-120833D01*
X303977Y-121417D01*
X303660Y-121917D01*
X303280Y-122250D01*
X302773Y-122500D01*
X301507D01*
G01X306417D02*
X308000Y-117500D01*
X309583Y-122500D01*
G01X309013Y-120750D02*
X306987D01*
G01X313100Y-117500D02*
Y-122500D01*
G01X311643Y-117500D02*
X314557D01*
G01X319467Y-122500D02*
X316933D01*
Y-117500D01*
X319467D01*
G01X318453Y-119917D02*
X316933D01*
G01X323300Y-122667D02*
X323173Y-122583D01*
Y-122417D01*
X323300Y-122333D01*
X323427Y-122417D01*
Y-122583D01*
X323300Y-122667D01*
G01Y-120417D02*
X323173Y-120333D01*
Y-120167D01*
X323300Y-120083D01*
X323427Y-120167D01*
Y-120333D01*
X323300Y-120417D01*
G01X296000Y-62500D02*
Y-137500D01*
G01X294000Y-62500D02*
Y-137500D01*
G01X301633Y-97500D02*
Y-92500D01*
X303153D01*
X303660Y-92750D01*
X304040Y-93333D01*
X304167Y-94000D01*
X304040Y-94667D01*
X303723Y-95167D01*
X303153Y-95417D01*
X301633D01*
G01X306860Y-97667D02*
X309140Y-92500D01*
G01X311643Y-97500D02*
Y-92500D01*
X314557Y-97500D01*
Y-92500D01*
G01X318200Y-97667D02*
X318073Y-97583D01*
Y-97417D01*
X318200Y-97333D01*
X318327Y-97417D01*
Y-97583D01*
X318200Y-97667D01*
G01Y-95417D02*
X318073Y-95333D01*
Y-95167D01*
X318200Y-95083D01*
X318327Y-95167D01*
Y-95333D01*
X318200Y-95417D01*
G01X296000Y-112500D02*
X496000D01*
G01X301633Y-72500D02*
Y-67500D01*
X303153D01*
X303660Y-67750D01*
X304040Y-68333D01*
X304167Y-69000D01*
X304040Y-69667D01*
X303723Y-70167D01*
X303153Y-70417D01*
X301633D01*
G01X306733Y-72500D02*
Y-67500D01*
X308317D01*
X308823Y-67750D01*
X309140Y-68083D01*
X309267Y-68750D01*
X309140Y-69417D01*
X308760Y-69833D01*
X308317Y-70083D01*
X306733D01*
G01X308317D02*
X309267Y-72500D01*
G01X313100D02*
X312593Y-72417D01*
X312150Y-72083D01*
X311770Y-71583D01*
X311517Y-71000D01*
X311390Y-70333D01*
Y-69667D01*
X311517Y-69000D01*
X311770Y-68417D01*
X312150Y-67917D01*
X312593Y-67583D01*
X313100Y-67500D01*
X313607Y-67583D01*
X314050Y-67917D01*
X314430Y-68417D01*
X314683Y-69000D01*
X314810Y-69667D01*
Y-70333D01*
X314683Y-71000D01*
X314430Y-71583D01*
X314050Y-72083D01*
X313607Y-72417D01*
X313100Y-72500D01*
G01X316933Y-71500D02*
X317250Y-72000D01*
X317630Y-72333D01*
X318073Y-72500D01*
X318580Y-72333D01*
X318960Y-72000D01*
X319340Y-71500D01*
X319467Y-70833D01*
Y-67500D01*
G01X324567Y-72500D02*
X322033D01*
Y-67500D01*
X324567D01*
G01X323553Y-69917D02*
X322033D01*
G01X329793Y-67917D02*
X329413Y-67667D01*
X328970Y-67500D01*
X328463D01*
X327893Y-67750D01*
X327450Y-68167D01*
X327133Y-68667D01*
X326880Y-69500D01*
X326817Y-70250D01*
X326943Y-71000D01*
X327133Y-71500D01*
X327513Y-72000D01*
X327957Y-72333D01*
X328400Y-72500D01*
X328843D01*
X329287Y-72333D01*
X329667Y-72083D01*
X329983Y-71750D01*
G01X333500Y-67500D02*
Y-72500D01*
G01X332043Y-67500D02*
X334957D01*
G01X338600Y-72667D02*
X338473Y-72583D01*
Y-72417D01*
X338600Y-72333D01*
X338727Y-72417D01*
Y-72583D01*
X338600Y-72667D01*
G01Y-70417D02*
X338473Y-70333D01*
Y-70167D01*
X338600Y-70083D01*
X338727Y-70167D01*
Y-70333D01*
X338600Y-70417D01*
G01X296000Y-87500D02*
X496000D01*
G01X411000Y-112500D02*
Y-137500D01*
G01X416633Y-122500D02*
Y-117500D01*
X418217D01*
X418723Y-117750D01*
X419040Y-118083D01*
X419167Y-118750D01*
X419040Y-119417D01*
X418660Y-119833D01*
X418217Y-120083D01*
X416633D01*
G01X418217D02*
X419167Y-122500D01*
G01X424267D02*
X421733D01*
Y-117500D01*
X424267D01*
G01X423253Y-119917D02*
X421733D01*
G01X426517Y-117500D02*
X428100Y-122500D01*
X429683Y-117500D01*
G01X433200Y-122667D02*
X433073Y-122583D01*
Y-122417D01*
X433200Y-122333D01*
X433327Y-122417D01*
Y-122583D01*
X433200Y-122667D01*
G01Y-120417D02*
X433073Y-120333D01*
Y-120167D01*
X433200Y-120083D01*
X433327Y-120167D01*
Y-120333D01*
X433200Y-120417D01*
G01X460000Y-112500D02*
Y-137500D01*
G01X-723776Y2987387D02*
Y-376795D01*
Y-489221D01*
X1782976D01*
Y-376795D01*
Y2987387D01*
X-723776D01*
G01X6705Y-124160D02*
X7332Y-124685D01*
X8037Y-125000D01*
X8663D01*
X9290Y-124685D01*
X9760Y-124160D01*
X9995Y-123425D01*
X9838Y-122690D01*
X9447Y-122060D01*
X8742Y-121640D01*
X7802Y-121430D01*
X7253Y-121010D01*
X7018Y-120275D01*
X7175Y-119540D01*
X7567Y-119015D01*
X8115Y-118700D01*
X8663D01*
X9212Y-118910D01*
X9682Y-119435D01*
G01X13005Y-125000D02*
Y-118700D01*
G01X16295D02*
Y-125000D01*
G01Y-121850D02*
X13005D01*
G01X20010Y-118700D02*
X21890D01*
G01X20950D02*
Y-125000D01*
G01X20010D02*
X21890D01*
G01X28817D02*
X25683D01*
Y-118700D01*
X28817D01*
G01X27563Y-121745D02*
X25683D01*
G01X31748Y-125000D02*
Y-118700D01*
X35352Y-125000D01*
Y-118700D01*
G01X39693Y-126155D02*
X40007Y-124790D01*
G01X46150Y-118700D02*
Y-125000D01*
G01X44348Y-118700D02*
X47952D01*
G01X50492Y-125000D02*
X52450Y-118700D01*
X54408Y-125000D01*
G01X53703Y-122795D02*
X51197D01*
G01X57810Y-118700D02*
X59690D01*
G01X58750D02*
Y-125000D01*
G01X57810D02*
X59690D01*
G01X62700Y-118700D02*
X63797Y-125000D01*
X65050Y-118700D01*
X66303Y-125000D01*
X67400Y-118700D01*
G01X69392Y-125000D02*
X71350Y-118700D01*
X73308Y-125000D01*
G01X72603Y-122795D02*
X70097D01*
G01X75848Y-125000D02*
Y-118700D01*
X79452Y-125000D01*
Y-118700D01*
G01X88683Y-125000D02*
Y-118700D01*
X90642D01*
X91268Y-119015D01*
X91660Y-119435D01*
X91817Y-120275D01*
X91660Y-121115D01*
X91190Y-121640D01*
X90642Y-121955D01*
X88683D01*
G01X90642D02*
X91817Y-125000D01*
G01X96550Y-125210D02*
X96393Y-125105D01*
Y-124895D01*
X96550Y-124790D01*
X96707Y-124895D01*
Y-125105D01*
X96550Y-125210D01*
G01X102850Y-125000D02*
X102223Y-124895D01*
X101675Y-124475D01*
X101205Y-123845D01*
X100892Y-123110D01*
X100735Y-122270D01*
Y-121430D01*
X100892Y-120590D01*
X101205Y-119855D01*
X101675Y-119225D01*
X102223Y-118805D01*
X102850Y-118700D01*
X103477Y-118805D01*
X104025Y-119225D01*
X104495Y-119855D01*
X104808Y-120590D01*
X104965Y-121430D01*
Y-122270D01*
X104808Y-123110D01*
X104495Y-123845D01*
X104025Y-124475D01*
X103477Y-124895D01*
X102850Y-125000D01*
G01X109150Y-125210D02*
X108993Y-125105D01*
Y-124895D01*
X109150Y-124790D01*
X109307Y-124895D01*
Y-125105D01*
X109150Y-125210D01*
G01X117173Y-119225D02*
X116703Y-118910D01*
X116155Y-118700D01*
X115528D01*
X114823Y-119015D01*
X114275Y-119540D01*
X113883Y-120170D01*
X113570Y-121220D01*
X113492Y-122165D01*
X113648Y-123110D01*
X113883Y-123740D01*
X114353Y-124370D01*
X114902Y-124790D01*
X115450Y-125000D01*
X115998D01*
X116547Y-124790D01*
X117017Y-124475D01*
X117408Y-124055D01*
G01X121750Y-125210D02*
X121593Y-125105D01*
Y-124895D01*
X121750Y-124790D01*
X121907Y-124895D01*
Y-125105D01*
X121750Y-125210D01*
G01X6627Y-115000D02*
Y-108700D01*
G01X9603D02*
X6627Y-112585D01*
G01X10073Y-115000D02*
X7958Y-110800D01*
G01X12927Y-108700D02*
Y-113215D01*
X13240Y-114160D01*
X13867Y-114790D01*
X14650Y-115000D01*
X15433Y-114790D01*
X16060Y-114160D01*
X16373Y-113215D01*
Y-108700D01*
G01X22517Y-115000D02*
X19383D01*
Y-108700D01*
X22517D01*
G01X21263Y-111745D02*
X19383D01*
G01X26310Y-108700D02*
X28190D01*
G01X27250D02*
Y-115000D01*
G01X26310D02*
X28190D01*
G01X38205Y-114160D02*
X38832Y-114685D01*
X39537Y-115000D01*
X40163D01*
X40790Y-114685D01*
X41260Y-114160D01*
X41495Y-113425D01*
X41338Y-112690D01*
X40947Y-112060D01*
X40242Y-111640D01*
X39302Y-111430D01*
X38753Y-111010D01*
X38518Y-110275D01*
X38675Y-109540D01*
X39067Y-109015D01*
X39615Y-108700D01*
X40163D01*
X40712Y-108910D01*
X41182Y-109435D01*
G01X44505Y-115000D02*
Y-108700D01*
G01X47795D02*
Y-115000D01*
G01Y-111850D02*
X44505D01*
G01X50492Y-115000D02*
X52450Y-108700D01*
X54408Y-115000D01*
G01X53703Y-112795D02*
X51197D01*
G01X56948Y-115000D02*
Y-108700D01*
X60552Y-115000D01*
Y-108700D01*
G01X69705Y-115000D02*
Y-108700D01*
G01X72995D02*
Y-115000D01*
G01Y-111850D02*
X69705D01*
G01X76005Y-114160D02*
X76632Y-114685D01*
X77337Y-115000D01*
X77963D01*
X78590Y-114685D01*
X79060Y-114160D01*
X79295Y-113425D01*
X79138Y-112690D01*
X78747Y-112060D01*
X78042Y-111640D01*
X77102Y-111430D01*
X76553Y-111010D01*
X76318Y-110275D01*
X76475Y-109540D01*
X76867Y-109015D01*
X77415Y-108700D01*
X77963D01*
X78512Y-108910D01*
X78982Y-109435D01*
G01X83010Y-108700D02*
X84890D01*
G01X83950D02*
Y-115000D01*
G01X83010D02*
X84890D01*
G01X88292D02*
X90250Y-108700D01*
X92208Y-115000D01*
G01X91503Y-112795D02*
X88997D01*
G01X94748Y-115000D02*
Y-108700D01*
X98352Y-115000D01*
Y-108700D01*
G01X103320Y-111850D02*
X104887D01*
Y-113740D01*
X104417Y-114370D01*
X103868Y-114790D01*
X103085Y-115000D01*
X102302Y-114790D01*
X101753Y-114370D01*
X101283Y-113740D01*
X100970Y-113005D01*
X100813Y-112165D01*
Y-111430D01*
X100970Y-110800D01*
X101283Y-110065D01*
X101753Y-109435D01*
X102223Y-109015D01*
X102850Y-108700D01*
X103398D01*
X104025Y-108910D01*
X104495Y-109330D01*
G01X108993Y-116155D02*
X109307Y-114790D01*
G01X115450Y-108700D02*
Y-115000D01*
G01X113648Y-108700D02*
X117252D01*
G01X119792Y-115000D02*
X121750Y-108700D01*
X123708Y-115000D01*
G01X123003Y-112795D02*
X120497D01*
G01X128050Y-115000D02*
X127423Y-114895D01*
X126875Y-114475D01*
X126405Y-113845D01*
X126092Y-113110D01*
X125935Y-112270D01*
Y-111430D01*
X126092Y-110590D01*
X126405Y-109855D01*
X126875Y-109225D01*
X127423Y-108805D01*
X128050Y-108700D01*
X128677Y-108805D01*
X129225Y-109225D01*
X129695Y-109855D01*
X130008Y-110590D01*
X130165Y-111430D01*
Y-112270D01*
X130008Y-113110D01*
X129695Y-113845D01*
X129225Y-114475D01*
X128677Y-114895D01*
X128050Y-115000D01*
G01X140650D02*
Y-112165D01*
X139083Y-108700D01*
G01X142217D02*
X140650Y-112165D01*
G01X145227Y-108700D02*
Y-113215D01*
X145540Y-114160D01*
X146167Y-114790D01*
X146950Y-115000D01*
X147733Y-114790D01*
X148360Y-114160D01*
X148673Y-113215D01*
Y-108700D01*
G01X151292Y-115000D02*
X153250Y-108700D01*
X155208Y-115000D01*
G01X154503Y-112795D02*
X151997D01*
G01X157748Y-115000D02*
Y-108700D01*
X161352Y-115000D01*
Y-108700D01*
G01X30650Y-92300D02*
X28130Y-91883D01*
X25925Y-90217D01*
X24035Y-87717D01*
X22775Y-84800D01*
X22145Y-81467D01*
Y-78133D01*
X22775Y-74800D01*
X24035Y-71883D01*
X25925Y-69384D01*
X28130Y-67717D01*
X30650Y-67300D01*
X33170Y-67717D01*
X35375Y-69384D01*
X37265Y-71883D01*
X38525Y-74800D01*
X39155Y-78133D01*
Y-81467D01*
X38525Y-84800D01*
X37265Y-87717D01*
X35375Y-90217D01*
X33170Y-91883D01*
X30650Y-92300D01*
G01X33170Y-85633D02*
X36950Y-92300D01*
G01X50495Y-75634D02*
Y-87300D01*
X51755Y-90217D01*
X53645Y-91883D01*
X55850Y-92300D01*
X58055Y-91883D01*
X59945Y-90217D01*
X61205Y-87300D01*
G01Y-92300D02*
Y-75634D01*
G01X86720Y-92300D02*
Y-75634D01*
G01Y-78550D02*
X85460Y-76884D01*
X83570Y-76050D01*
X81365Y-75634D01*
X79160Y-76467D01*
X77270Y-78133D01*
X76010Y-80634D01*
X75380Y-83967D01*
X76010Y-87300D01*
X77270Y-89801D01*
X79160Y-91467D01*
X81365Y-92300D01*
X83570Y-91883D01*
X85460Y-90634D01*
X86720Y-88967D01*
G01X100895Y-92300D02*
Y-75634D01*
G01Y-79800D02*
X102155Y-77717D01*
X104045Y-76050D01*
X106565Y-75634D01*
X108770Y-76050D01*
X110660Y-77717D01*
X111605Y-80634D01*
Y-92300D01*
G01X131450Y-67300D02*
Y-92300D01*
G01X127040Y-75634D02*
X135860D01*
G01X162320Y-92300D02*
Y-75634D01*
G01Y-78550D02*
X161060Y-76884D01*
X159170Y-76050D01*
X156965Y-75634D01*
X154760Y-76467D01*
X152870Y-78133D01*
X151610Y-80634D01*
X150980Y-83967D01*
X151610Y-87300D01*
X152870Y-89801D01*
X154760Y-91467D01*
X156965Y-92300D01*
X159170Y-91883D01*
X161060Y-90634D01*
X162320Y-88967D01*
G01X6548Y-105000D02*
Y-98700D01*
X10152Y-105000D01*
Y-98700D01*
G01X14650Y-105000D02*
X14023Y-104895D01*
X13475Y-104475D01*
X13005Y-103845D01*
X12692Y-103110D01*
X12535Y-102270D01*
Y-101430D01*
X12692Y-100590D01*
X13005Y-99855D01*
X13475Y-99225D01*
X14023Y-98805D01*
X14650Y-98700D01*
X15277Y-98805D01*
X15825Y-99225D01*
X16295Y-99855D01*
X16608Y-100590D01*
X16765Y-101430D01*
Y-102270D01*
X16608Y-103110D01*
X16295Y-103845D01*
X15825Y-104475D01*
X15277Y-104895D01*
X14650Y-105000D01*
G01X20950Y-105210D02*
X20793Y-105105D01*
Y-104895D01*
X20950Y-104790D01*
X21107Y-104895D01*
Y-105105D01*
X20950Y-105210D01*
G01X27250Y-105000D02*
Y-98700D01*
X26310Y-99960D01*
G01Y-105000D02*
X28190D01*
G01X33550D02*
X34098Y-104895D01*
X34725Y-104580D01*
X35117Y-104055D01*
X35273Y-103320D01*
X35117Y-102585D01*
X34647Y-101955D01*
X33942Y-101640D01*
X33158D01*
X32688Y-101430D01*
X32297Y-100905D01*
X32140Y-100170D01*
X32375Y-99435D01*
X32923Y-98910D01*
X33550Y-98700D01*
X34177Y-98910D01*
X34725Y-99435D01*
X34960Y-100170D01*
X34803Y-100905D01*
X34412Y-101430D01*
X33942Y-101640D01*
X33158D01*
X32453Y-101955D01*
X31983Y-102585D01*
X31827Y-103320D01*
X31983Y-104055D01*
X32375Y-104580D01*
X33002Y-104895D01*
X33550Y-105000D01*
G01X39850D02*
X40398Y-104895D01*
X41025Y-104580D01*
X41417Y-104055D01*
X41573Y-103320D01*
X41417Y-102585D01*
X40947Y-101955D01*
X40242Y-101640D01*
X39458D01*
X38988Y-101430D01*
X38597Y-100905D01*
X38440Y-100170D01*
X38675Y-99435D01*
X39223Y-98910D01*
X39850Y-98700D01*
X40477Y-98910D01*
X41025Y-99435D01*
X41260Y-100170D01*
X41103Y-100905D01*
X40712Y-101430D01*
X40242Y-101640D01*
X39458D01*
X38753Y-101955D01*
X38283Y-102585D01*
X38127Y-103320D01*
X38283Y-104055D01*
X38675Y-104580D01*
X39302Y-104895D01*
X39850Y-105000D01*
G01X45993Y-106155D02*
X46307Y-104790D01*
G01X50100Y-98700D02*
X51197Y-105000D01*
X52450Y-98700D01*
X53703Y-105000D01*
X54800Y-98700D01*
G01X60317Y-105000D02*
X57183D01*
Y-98700D01*
X60317D01*
G01X59063Y-101745D02*
X57183D01*
G01X63248Y-105000D02*
Y-98700D01*
X66852Y-105000D01*
Y-98700D01*
G01X76005Y-105000D02*
Y-98700D01*
G01X79295D02*
Y-105000D01*
G01Y-101850D02*
X76005D01*
G01X81600Y-98700D02*
X82697Y-105000D01*
X83950Y-98700D01*
X85203Y-105000D01*
X86300Y-98700D01*
G01X88292Y-105000D02*
X90250Y-98700D01*
X92208Y-105000D01*
G01X91503Y-102795D02*
X88997D01*
G01X101362Y-99750D02*
X101832Y-99120D01*
X102380Y-98805D01*
X103007Y-98700D01*
X103790Y-98910D01*
X104338Y-99435D01*
X104495Y-100065D01*
X104417Y-100695D01*
X104103Y-101220D01*
X102537Y-102270D01*
X101832Y-103005D01*
X101362Y-104055D01*
X101205Y-105000D01*
X104495D01*
G01X107348D02*
Y-98700D01*
X110952Y-105000D01*
Y-98700D01*
G01X113727Y-105000D02*
Y-98700D01*
X115293D01*
X115920Y-99015D01*
X116390Y-99435D01*
X116782Y-100065D01*
X117095Y-100800D01*
X117173Y-101850D01*
X117095Y-102900D01*
X116782Y-103635D01*
X116390Y-104265D01*
X115920Y-104685D01*
X115293Y-105000D01*
X113727D01*
G01X126483D02*
Y-98700D01*
X128442D01*
X129068Y-99015D01*
X129460Y-99435D01*
X129617Y-100275D01*
X129460Y-101115D01*
X128990Y-101640D01*
X128442Y-101955D01*
X126483D01*
G01X128442D02*
X129617Y-105000D01*
G01X132627D02*
Y-98700D01*
X134193D01*
X134820Y-99015D01*
X135290Y-99435D01*
X135682Y-100065D01*
X135995Y-100800D01*
X136073Y-101850D01*
X135995Y-102900D01*
X135682Y-103635D01*
X135290Y-104265D01*
X134820Y-104685D01*
X134193Y-105000D01*
X132627D01*
G01X140650Y-105210D02*
X140493Y-105105D01*
Y-104895D01*
X140650Y-104790D01*
X140807Y-104895D01*
Y-105105D01*
X140650Y-105210D01*
G01X202000Y-72000D02*
Y-80000D01*
X206000D01*
G01X213800D02*
Y-74667D01*
G01Y-75600D02*
X213400Y-75067D01*
X212800Y-74800D01*
X212100Y-74667D01*
X211400Y-74933D01*
X210800Y-75467D01*
X210400Y-76267D01*
X210200Y-77333D01*
X210400Y-78400D01*
X210800Y-79200D01*
X211400Y-79733D01*
X212100Y-80000D01*
X212800Y-79867D01*
X213400Y-79467D01*
X213800Y-78934D01*
G01X217900Y-82400D02*
X218500Y-82667D01*
X219300Y-82400D01*
X219800Y-81867D01*
X220200Y-81200D01*
X220800Y-79067D01*
X222100Y-74667D01*
G01X218900D02*
X220800Y-79067D01*
G01X226500Y-76400D02*
X229700D01*
X229400Y-75467D01*
X228900Y-74933D01*
X228200Y-74667D01*
X227500Y-74800D01*
X226900Y-75200D01*
X226500Y-76133D01*
X226300Y-76934D01*
Y-77733D01*
X226500Y-78533D01*
X227000Y-79333D01*
X227600Y-79867D01*
X228300Y-80000D01*
X229000Y-79733D01*
X229700Y-78934D01*
G01X234600Y-80000D02*
Y-74667D01*
G01Y-75733D02*
X235100Y-75200D01*
X235600Y-74800D01*
X236300Y-74667D01*
X236800Y-74800D01*
X237400Y-75200D01*
G01X225500Y-122000D02*
Y-130000D01*
G01X223200Y-122000D02*
X227800D01*
G01X233500Y-124667D02*
Y-130000D01*
G01Y-122533D02*
X233300Y-122400D01*
Y-122133D01*
X233500Y-122000D01*
X233700Y-122133D01*
Y-122400D01*
X233500Y-122533D01*
G01X239800Y-130000D02*
Y-124667D01*
G01Y-126000D02*
X240200Y-125333D01*
X240800Y-124800D01*
X241600Y-124667D01*
X242300Y-124800D01*
X242900Y-125333D01*
X243200Y-126267D01*
Y-130000D01*
G01X251300D02*
Y-124667D01*
G01Y-125600D02*
X250900Y-125067D01*
X250300Y-124800D01*
X249600Y-124667D01*
X248900Y-124933D01*
X248300Y-125467D01*
X247900Y-126267D01*
X247700Y-127333D01*
X247900Y-128400D01*
X248300Y-129200D01*
X248900Y-129733D01*
X249600Y-130000D01*
X250300Y-129867D01*
X250900Y-129467D01*
X251300Y-128934D01*
G01X234300Y-97000D02*
X236700D01*
G01X235500D02*
Y-105000D01*
G01X234300D02*
X236700D01*
G01X241200D02*
Y-97000D01*
X245800Y-105000D01*
Y-97000D01*
G01X249600Y-98333D02*
X250200Y-97533D01*
X250900Y-97133D01*
X251700Y-97000D01*
X252700Y-97267D01*
X253400Y-97933D01*
X253600Y-98733D01*
X253500Y-99534D01*
X253100Y-100200D01*
X251100Y-101533D01*
X250200Y-102467D01*
X249600Y-103800D01*
X249400Y-105000D01*
X253600D01*
G01Y-76667D02*
X254300Y-75733D01*
X254900Y-75200D01*
X255700Y-74933D01*
X256400Y-75200D01*
X256900Y-75733D01*
X257300Y-76533D01*
X257400Y-77467D01*
X257300Y-78267D01*
X256900Y-79067D01*
X256300Y-79733D01*
X255600Y-80000D01*
X254800Y-79733D01*
X254100Y-78934D01*
X253700Y-77733D01*
X253600Y-76400D01*
X253800Y-74667D01*
X254100Y-73733D01*
X254600Y-72800D01*
X255300Y-72133D01*
X256000Y-72000D01*
X256700Y-72267D01*
X257200Y-72933D01*
G01X328600Y-123333D02*
X329200Y-122533D01*
X329900Y-122133D01*
X330700Y-122000D01*
X331700Y-122267D01*
X332400Y-122933D01*
X332600Y-123733D01*
X332500Y-124534D01*
X332100Y-125200D01*
X330100Y-126533D01*
X329200Y-127467D01*
X328600Y-128800D01*
X328400Y-130000D01*
X332600D01*
G01X338500Y-122000D02*
X337700Y-122267D01*
X337100Y-122933D01*
X336700Y-123733D01*
X336400Y-124800D01*
X336300Y-126000D01*
X336400Y-127200D01*
X336700Y-128267D01*
X337100Y-129067D01*
X337700Y-129733D01*
X338500Y-130000D01*
X339300Y-129733D01*
X339900Y-129067D01*
X340300Y-128267D01*
X340600Y-127200D01*
X340700Y-126000D01*
X340600Y-124800D01*
X340300Y-123733D01*
X339900Y-122933D01*
X339300Y-122267D01*
X338500Y-122000D01*
G01X346500Y-130000D02*
Y-122000D01*
X345300Y-123600D01*
G01Y-130000D02*
X347700D01*
G01X352300Y-128400D02*
X352900Y-129333D01*
X353700Y-129867D01*
X354600Y-130000D01*
X355400Y-129867D01*
X356200Y-129200D01*
X356700Y-128400D01*
X356800Y-127600D01*
X356600Y-126667D01*
X355900Y-126000D01*
X355200Y-125733D01*
X354300D01*
G01X355200D02*
X355800Y-125333D01*
X356300Y-124667D01*
X356500Y-123867D01*
X356300Y-123067D01*
X355800Y-122400D01*
X354900Y-122000D01*
X354000Y-122133D01*
X353100Y-122667D01*
G01X360700Y-130267D02*
X364300Y-122000D01*
G01X370500D02*
X369700Y-122267D01*
X369100Y-122933D01*
X368700Y-123733D01*
X368400Y-124800D01*
X368300Y-126000D01*
X368400Y-127200D01*
X368700Y-128267D01*
X369100Y-129067D01*
X369700Y-129733D01*
X370500Y-130000D01*
X371300Y-129733D01*
X371900Y-129067D01*
X372300Y-128267D01*
X372600Y-127200D01*
X372700Y-126000D01*
X372600Y-124800D01*
X372300Y-123733D01*
X371900Y-122933D01*
X371300Y-122267D01*
X370500Y-122000D01*
G01X378500Y-130000D02*
Y-122000D01*
X377300Y-123600D01*
G01Y-130000D02*
X379700D01*
G01X384700Y-130267D02*
X388300Y-122000D01*
G01X394500D02*
X393700Y-122267D01*
X393100Y-122933D01*
X392700Y-123733D01*
X392400Y-124800D01*
X392300Y-126000D01*
X392400Y-127200D01*
X392700Y-128267D01*
X393100Y-129067D01*
X393700Y-129733D01*
X394500Y-130000D01*
X395300Y-129733D01*
X395900Y-129067D01*
X396300Y-128267D01*
X396600Y-127200D01*
X396700Y-126000D01*
X396600Y-124800D01*
X396300Y-123733D01*
X395900Y-122933D01*
X395300Y-122267D01*
X394500Y-122000D01*
G01X400800Y-129067D02*
X401500Y-129733D01*
X402300Y-130000D01*
X403100Y-129733D01*
X403800Y-128934D01*
X404300Y-127733D01*
X404500Y-126533D01*
Y-125067D01*
X404300Y-123867D01*
X403800Y-122800D01*
X403200Y-122267D01*
X402500Y-122000D01*
X401700Y-122267D01*
X401100Y-122800D01*
X400700Y-123600D01*
X400500Y-124667D01*
X400700Y-125600D01*
X401200Y-126533D01*
X401800Y-127067D01*
X402500Y-127200D01*
X403300Y-126934D01*
X403900Y-126267D01*
X404500Y-125067D01*
G01X328300Y-105000D02*
Y-97000D01*
X330300D01*
X331100Y-97400D01*
X331700Y-97933D01*
X332200Y-98733D01*
X332600Y-99667D01*
X332700Y-101000D01*
X332600Y-102333D01*
X332200Y-103267D01*
X331700Y-104067D01*
X331100Y-104600D01*
X330300Y-105000D01*
X328300D01*
G01X336000D02*
X338500Y-97000D01*
X341000Y-105000D01*
G01X340100Y-102200D02*
X336900D01*
G01X346500Y-97000D02*
Y-105000D01*
G01X344200Y-97000D02*
X348800D01*
G01X352600Y-101667D02*
X353300Y-100733D01*
X353900Y-100200D01*
X354700Y-99933D01*
X355400Y-100200D01*
X355900Y-100733D01*
X356300Y-101533D01*
X356400Y-102467D01*
X356300Y-103267D01*
X355900Y-104067D01*
X355300Y-104733D01*
X354600Y-105000D01*
X353800Y-104733D01*
X353100Y-103934D01*
X352700Y-102733D01*
X352600Y-101400D01*
X352800Y-99667D01*
X353100Y-98733D01*
X353600Y-97800D01*
X354300Y-97133D01*
X355000Y-97000D01*
X355700Y-97267D01*
X356200Y-97933D01*
G01X359900Y-105000D02*
Y-97000D01*
X362500Y-103667D01*
X365100Y-97000D01*
Y-105000D01*
G01X370500Y-97000D02*
Y-105000D01*
G01X368200Y-97000D02*
X372800D01*
G01X379300Y-100733D02*
X379700Y-100333D01*
X380000Y-99667D01*
X380200Y-98733D01*
X380000Y-97933D01*
X379600Y-97400D01*
X378900Y-97000D01*
X376200D01*
Y-105000D01*
X379500D01*
X380200Y-104467D01*
X380600Y-103667D01*
X380800Y-102733D01*
X380600Y-101800D01*
X380000Y-101000D01*
X379300Y-100733D01*
X376200D01*
G01X386500Y-105000D02*
X387200Y-104867D01*
X388000Y-104467D01*
X388500Y-103800D01*
X388700Y-102867D01*
X388500Y-101934D01*
X387900Y-101133D01*
X387000Y-100733D01*
X386000D01*
X385400Y-100467D01*
X384900Y-99800D01*
X384700Y-98867D01*
X385000Y-97933D01*
X385700Y-97267D01*
X386500Y-97000D01*
X387300Y-97267D01*
X388000Y-97933D01*
X388300Y-98867D01*
X388100Y-99800D01*
X387600Y-100467D01*
X387000Y-100733D01*
X386000D01*
X385100Y-101133D01*
X384500Y-101934D01*
X384300Y-102867D01*
X384500Y-103800D01*
X385000Y-104467D01*
X385800Y-104867D01*
X386500Y-105000D01*
G01X394500D02*
X395200Y-104867D01*
X396000Y-104467D01*
X396500Y-103800D01*
X396700Y-102867D01*
X396500Y-101934D01*
X395900Y-101133D01*
X395000Y-100733D01*
X394000D01*
X393400Y-100467D01*
X392900Y-99800D01*
X392700Y-98867D01*
X393000Y-97933D01*
X393700Y-97267D01*
X394500Y-97000D01*
X395300Y-97267D01*
X396000Y-97933D01*
X396300Y-98867D01*
X396100Y-99800D01*
X395600Y-100467D01*
X395000Y-100733D01*
X394000D01*
X393100Y-101133D01*
X392500Y-101934D01*
X392300Y-102867D01*
X392500Y-103800D01*
X393000Y-104467D01*
X393800Y-104867D01*
X394500Y-105000D01*
G01X400000D02*
X402500Y-97000D01*
X405000Y-105000D01*
G01X404100Y-102200D02*
X400900D01*
G01X410500Y-97000D02*
X409700Y-97267D01*
X409100Y-97933D01*
X408700Y-98733D01*
X408400Y-99800D01*
X408300Y-101000D01*
X408400Y-102200D01*
X408700Y-103267D01*
X409100Y-104067D01*
X409700Y-104733D01*
X410500Y-105000D01*
X411300Y-104733D01*
X411900Y-104067D01*
X412300Y-103267D01*
X412600Y-102200D01*
X412700Y-101000D01*
X412600Y-99800D01*
X412300Y-98733D01*
X411900Y-97933D01*
X411300Y-97267D01*
X410500Y-97000D01*
G01X350500Y-72000D02*
Y-80000D01*
G01X348200Y-72000D02*
X352800D01*
G01X356600Y-76667D02*
X357300Y-75733D01*
X357900Y-75200D01*
X358700Y-74933D01*
X359400Y-75200D01*
X359900Y-75733D01*
X360300Y-76533D01*
X360400Y-77467D01*
X360300Y-78267D01*
X359900Y-79067D01*
X359300Y-79733D01*
X358600Y-80000D01*
X357800Y-79733D01*
X357100Y-78934D01*
X356700Y-77733D01*
X356600Y-76400D01*
X356800Y-74667D01*
X357100Y-73733D01*
X357600Y-72800D01*
X358300Y-72133D01*
X359000Y-72000D01*
X359700Y-72267D01*
X360200Y-72933D01*
G01X363900Y-80000D02*
Y-72000D01*
X366500Y-78667D01*
X369100Y-72000D01*
Y-80000D01*
G01X375100Y-76000D02*
X377100D01*
Y-78400D01*
X376500Y-79200D01*
X375800Y-79733D01*
X374800Y-80000D01*
X373800Y-79733D01*
X373100Y-79200D01*
X372500Y-78400D01*
X372100Y-77467D01*
X371900Y-76400D01*
Y-75467D01*
X372100Y-74667D01*
X372500Y-73733D01*
X373100Y-72933D01*
X373700Y-72400D01*
X374500Y-72000D01*
X375200D01*
X376000Y-72267D01*
X376600Y-72800D01*
G01X379500Y-82667D02*
X385500D01*
G01X388500Y-80000D02*
Y-72000D01*
X390900D01*
X391700Y-72400D01*
X392300Y-73333D01*
X392500Y-74400D01*
X392300Y-75467D01*
X391800Y-76267D01*
X390900Y-76667D01*
X388500D01*
G01X396300Y-80000D02*
Y-72000D01*
X398300D01*
X399100Y-72400D01*
X399700Y-72933D01*
X400200Y-73733D01*
X400600Y-74667D01*
X400700Y-76000D01*
X400600Y-77333D01*
X400200Y-78267D01*
X399700Y-79067D01*
X399100Y-79600D01*
X398300Y-80000D01*
X396300D01*
G01X407300Y-75733D02*
X407700Y-75333D01*
X408000Y-74667D01*
X408200Y-73733D01*
X408000Y-72933D01*
X407600Y-72400D01*
X406900Y-72000D01*
X404200D01*
Y-80000D01*
X407500D01*
X408200Y-79467D01*
X408600Y-78667D01*
X408800Y-77733D01*
X408600Y-76800D01*
X408000Y-76000D01*
X407300Y-75733D01*
X404200D01*
G01X411500Y-82667D02*
X417500D01*
G01X420000Y-80000D02*
X422500Y-72000D01*
X425000Y-80000D01*
G01X424100Y-77200D02*
X420900D01*
G01X427500Y-82667D02*
X433500D01*
G01X439300Y-75733D02*
X439700Y-75333D01*
X440000Y-74667D01*
X440200Y-73733D01*
X440000Y-72933D01*
X439600Y-72400D01*
X438900Y-72000D01*
X436200D01*
Y-80000D01*
X439500D01*
X440200Y-79467D01*
X440600Y-78667D01*
X440800Y-77733D01*
X440600Y-76800D01*
X440000Y-76000D01*
X439300Y-75733D01*
X436200D01*
G01X444300Y-80000D02*
Y-72000D01*
X446300D01*
X447100Y-72400D01*
X447700Y-72933D01*
X448200Y-73733D01*
X448600Y-74667D01*
X448700Y-76000D01*
X448600Y-77333D01*
X448200Y-78267D01*
X447700Y-79067D01*
X447100Y-79600D01*
X446300Y-80000D01*
X444300D01*
G01X443000Y-130000D02*
X445500Y-122000D01*
X448000Y-130000D01*
G01X447100Y-127200D02*
X443900D01*
G01X473000Y-130000D02*
Y-122000D01*
X471800Y-123600D01*
G01Y-130000D02*
X474200D01*
G01X479100Y-126667D02*
X479800Y-125733D01*
X480400Y-125200D01*
X481200Y-124933D01*
X481900Y-125200D01*
X482400Y-125733D01*
X482800Y-126533D01*
X482900Y-127467D01*
X482800Y-128267D01*
X482400Y-129067D01*
X481800Y-129733D01*
X481100Y-130000D01*
X480300Y-129733D01*
X479600Y-128934D01*
X479200Y-127733D01*
X479100Y-126400D01*
X479300Y-124667D01*
X479600Y-123733D01*
X480100Y-122800D01*
X480800Y-122133D01*
X481500Y-122000D01*
X482200Y-122267D01*
X482700Y-122933D01*
G54D12*
G01X374431Y1901397D02*
X384819Y1891009D01*
Y1800894D01*
X375710Y1791785D01*
X337391D01*
X330979Y1785373D01*
Y1766224D01*
X319054Y1754299D01*
X167640D01*
X163594Y1750253D01*
X98689D01*
X80376Y1768566D01*
G01D02*
Y1772098D01*
G01D02*
Y1775609D01*
X15547Y723112D03*
X25389D03*
X15547Y746734D03*
X7673Y734923D03*
X25389Y770357D03*
Y778231D03*
X15547Y801853D03*
X25389Y786105D03*
X7673Y797915D03*
Y805790D03*
X15547Y809727D03*
Y817601D03*
X7673Y813664D03*
Y821538D03*
X15547Y872719D03*
X7673Y868782D03*
Y876656D03*
X15547Y880593D03*
Y888467D03*
X7673Y892404D03*
X15547Y927837D03*
Y935711D03*
Y951459D03*
X25389Y943585D03*
Y951459D03*
X7673Y931774D03*
Y939648D03*
Y947522D03*
X25389Y959333D03*
Y967207D03*
X7673Y963270D03*
X15547Y998703D03*
X7673Y1002640D03*
Y1010514D03*
X15547Y1006577D03*
Y1014451D03*
Y1022325D03*
X25389Y1014451D03*
X7673Y1026262D03*
X25393Y1065629D03*
X7677Y1093188D03*
X15551Y1097125D03*
Y1104999D03*
Y1112873D03*
X25393Y1104999D03*
Y1120748D03*
X7677Y1101062D03*
Y1116810D03*
X25393Y1128622D03*
X15551Y1152244D03*
Y1160118D03*
X25393Y1167992D03*
X7677Y1156180D03*
Y1164055D03*
X15551Y1175866D03*
X7677Y1171929D03*
X15551Y1215236D03*
X7677Y1211299D03*
X15551Y1223110D03*
Y1230984D03*
X25393Y1238858D03*
X7677Y1219173D03*
Y1234921D03*
X15551Y1246732D03*
X25393D03*
Y1262480D03*
Y1270354D03*
Y1286102D03*
X7677Y1266417D03*
Y1282165D03*
Y1313661D03*
X25393Y1317598D03*
X7677Y1360905D03*
X15551Y1356968D03*
X7677Y1376653D03*
X15551Y1364842D03*
X25393Y1372716D03*
X15551Y1388464D03*
X33263Y734923D03*
Y774293D03*
Y782167D03*
Y790041D03*
Y900278D03*
Y908152D03*
Y947522D03*
Y971144D03*
Y1010514D03*
Y1026262D03*
X33267Y1108936D03*
Y1164055D03*
Y1179803D03*
Y1187677D03*
Y1250669D03*
Y1360905D03*
Y1384527D03*
G54D13*
X23402Y1685410D03*
Y1701945D03*
Y1735016D03*
Y1751551D03*
Y1784622D03*
Y1801158D03*
G54D14*
X45411Y505996D03*
Y568004D03*
Y1564000D03*
Y1626008D03*
G54D15*
X64979Y55500D03*
X54979Y50500D03*
X64979Y171500D03*
X54979Y176500D03*
X64979Y181500D03*
Y191500D03*
Y201500D03*
X54979Y186500D03*
Y196500D03*
Y206500D03*
X64979Y244500D03*
X54979Y249500D03*
X64979Y254500D03*
Y264500D03*
Y274500D03*
X54979Y269500D03*
Y279500D03*
Y395500D03*
X189762Y73105D03*
X190289Y152050D03*
X190357Y247568D03*
X190817Y331786D03*
X189761Y421732D03*
X190553Y506517D03*
X192888Y598130D03*
X190816Y681645D03*
X191846Y774526D03*
X191606Y856244D03*
X196311Y947202D03*
X191250Y1122856D03*
X191342Y1206233D03*
X191846Y1299104D03*
X190552Y1380966D03*
X189463Y1474162D03*
X191079Y1557277D03*
X192143Y1648177D03*
X191607Y1731351D03*
X191530Y1823227D03*
X190289Y1900420D03*
X192125Y1998730D03*
X191530Y2043388D03*
G54D16*
X119920Y98071D03*
Y108071D03*
Y118071D03*
Y128071D03*
Y138071D03*
Y148071D03*
Y158071D03*
Y168071D03*
Y178071D03*
Y188071D03*
Y198071D03*
Y208071D03*
Y446102D03*
Y456102D03*
Y466102D03*
Y476102D03*
Y486102D03*
Y496102D03*
Y506102D03*
Y516102D03*
Y526102D03*
Y536102D03*
Y546102D03*
Y556102D03*
Y714134D03*
Y794134D03*
Y804134D03*
Y814134D03*
Y824134D03*
Y834134D03*
Y844134D03*
Y854134D03*
Y864134D03*
Y874134D03*
Y884134D03*
Y894134D03*
Y904134D03*
Y1142165D03*
Y1152165D03*
Y1162165D03*
Y1172165D03*
Y1182165D03*
Y1192165D03*
Y1202165D03*
Y1212165D03*
Y1222165D03*
Y1232165D03*
Y1242165D03*
Y1252165D03*
Y1490197D03*
Y1500197D03*
Y1510197D03*
Y1520197D03*
Y1530197D03*
Y1540197D03*
Y1550197D03*
Y1560197D03*
Y1570197D03*
Y1580197D03*
Y1590197D03*
Y1600197D03*
Y1758228D03*
Y1838228D03*
Y1848228D03*
Y1858228D03*
Y1868228D03*
Y1878228D03*
Y1888228D03*
Y1898228D03*
Y1908228D03*
Y1918228D03*
Y1928228D03*
Y1938228D03*
Y1948228D03*
X139920Y98071D03*
Y128071D03*
Y118071D03*
Y108071D03*
Y148071D03*
Y138071D03*
Y178071D03*
Y168071D03*
Y158071D03*
Y198071D03*
Y188071D03*
Y208071D03*
Y406102D03*
Y466102D03*
Y456102D03*
Y446102D03*
Y486102D03*
Y476102D03*
Y516102D03*
Y506102D03*
Y496102D03*
Y536102D03*
Y526102D03*
Y556102D03*
Y546102D03*
Y804134D03*
Y794134D03*
Y824134D03*
Y814134D03*
Y854134D03*
Y844134D03*
Y834134D03*
Y874134D03*
Y864134D03*
Y904134D03*
Y894134D03*
Y884134D03*
Y1122165D03*
Y1142165D03*
Y1162165D03*
Y1152165D03*
Y1192165D03*
Y1182165D03*
Y1172165D03*
Y1212165D03*
Y1202165D03*
Y1242165D03*
Y1232165D03*
Y1222165D03*
Y1252165D03*
Y1500197D03*
Y1490197D03*
Y1530197D03*
Y1520197D03*
Y1510197D03*
Y1550197D03*
Y1540197D03*
Y1580197D03*
Y1570197D03*
Y1560197D03*
Y1600197D03*
Y1590197D03*
Y1838228D03*
Y1868228D03*
Y1858228D03*
Y1848228D03*
Y1888228D03*
Y1878228D03*
Y1918228D03*
Y1908228D03*
Y1898228D03*
Y1938228D03*
Y1928228D03*
Y1948228D03*
G54D17*
X173385Y32520D03*
Y21890D03*
X183385Y32520D03*
Y21890D03*
X193385Y32520D03*
Y21890D03*
X173385Y196890D03*
X183385D03*
X193385D03*
X173385Y207520D03*
X183385D03*
X193385D03*
X173385Y371890D03*
X183385D03*
X193385D03*
X173385Y382520D03*
X183385D03*
X193385D03*
X173386Y557520D03*
Y546890D03*
X183386Y557520D03*
Y546890D03*
X193386Y557520D03*
Y546890D03*
X173386Y732520D03*
Y721890D03*
X183386Y732520D03*
Y721890D03*
X193386Y732520D03*
Y721890D03*
X173385Y896890D03*
X183385D03*
X193385D03*
X173385Y907520D03*
X183385D03*
X193385D03*
X173385Y1071890D03*
X183385D03*
X193385D03*
X173385Y1082520D03*
X183385D03*
X193385D03*
X173385Y1257520D03*
Y1246890D03*
X183385Y1257520D03*
Y1246890D03*
X193385Y1257520D03*
Y1246890D03*
X173385Y1432520D03*
Y1421890D03*
X183385Y1432520D03*
Y1421890D03*
X193385Y1432520D03*
Y1421890D03*
X173385Y1596890D03*
X183385D03*
X193385D03*
X173385Y1607520D03*
X183385D03*
X193385D03*
X173385Y1771890D03*
X183385D03*
X193385D03*
X173385Y1782520D03*
X183385D03*
X193385D03*
X173385Y1957520D03*
Y1946890D03*
X183385Y1957520D03*
Y1946890D03*
X193385Y1957520D03*
Y1946890D03*
X203385Y32520D03*
Y21890D03*
X213385Y32520D03*
Y21890D03*
X203385Y196890D03*
X213385D03*
X203385Y207520D03*
X213385D03*
X203385Y371890D03*
X213385D03*
X203385Y382520D03*
X213385D03*
X203386Y557520D03*
Y546890D03*
X213386Y557520D03*
Y546890D03*
X203386Y732520D03*
Y721890D03*
X213386Y732520D03*
Y721890D03*
X203385Y896890D03*
X213385D03*
X203385Y907520D03*
X213385D03*
X203385Y1071890D03*
X213385D03*
X203385Y1082520D03*
X213385D03*
X203385Y1257520D03*
Y1246890D03*
X213385Y1257520D03*
Y1246890D03*
X203385Y1432520D03*
Y1421890D03*
X213385Y1432520D03*
Y1421890D03*
X203385Y1596890D03*
X213385D03*
X203385Y1607520D03*
X213385D03*
X203385Y1771890D03*
X213385D03*
X203385Y1782520D03*
X213385D03*
X203385Y1957520D03*
Y1946890D03*
X213385Y1957520D03*
Y1946890D03*
X223385Y32520D03*
Y21890D03*
X233385Y32520D03*
Y21890D03*
X243385Y32520D03*
Y21890D03*
X223385Y196890D03*
X233385D03*
X243385D03*
X223385Y207520D03*
X233385D03*
X243385D03*
X223385Y371890D03*
X233385D03*
X243385D03*
X223385Y382520D03*
X233385D03*
X243385D03*
X223386Y557520D03*
Y546890D03*
X233386Y557520D03*
Y546890D03*
X243386Y557520D03*
Y546890D03*
X223386Y732520D03*
Y721890D03*
X233386Y732520D03*
Y721890D03*
X243386Y732520D03*
Y721890D03*
X223385Y896890D03*
X233385D03*
X243385D03*
X223385Y907520D03*
X233385D03*
X243385D03*
X223385Y1071890D03*
X233385D03*
X243385D03*
X223385Y1082520D03*
X233385D03*
X243385D03*
X223385Y1257520D03*
Y1246890D03*
X233385Y1257520D03*
Y1246890D03*
X243385Y1257520D03*
Y1246890D03*
X223385Y1432520D03*
Y1421890D03*
X233385Y1432520D03*
Y1421890D03*
X243385Y1432520D03*
Y1421890D03*
X223385Y1596890D03*
X233385D03*
X243385D03*
X223385Y1607520D03*
X233385D03*
X243385D03*
X223385Y1771890D03*
X233385D03*
X243385D03*
X223385Y1782520D03*
X233385D03*
X243385D03*
X223385Y1957520D03*
Y1946890D03*
X233385Y1957520D03*
Y1946890D03*
X243385Y1957520D03*
Y1946890D03*
X337165Y34705D03*
Y199705D03*
Y384705D03*
X337166Y549705D03*
Y734705D03*
X337165Y899705D03*
Y1084705D03*
Y1249705D03*
Y1434705D03*
Y1599705D03*
Y1949705D03*
X342165Y29705D03*
X347165Y24705D03*
Y34705D03*
X342165Y194705D03*
X357165Y199705D03*
X362165Y194705D03*
X357165Y209705D03*
X362165Y204705D03*
X342165Y379705D03*
X347165Y374705D03*
Y384705D03*
X342166Y544705D03*
X357166Y549705D03*
Y559705D03*
X362166Y544705D03*
Y554705D03*
X342166Y729705D03*
X347166Y724705D03*
Y734705D03*
X342165Y894705D03*
X357165Y899705D03*
X362165Y894705D03*
X357165Y909705D03*
X362165Y904705D03*
X342165Y1079705D03*
X347165Y1074705D03*
Y1084705D03*
X342165Y1244705D03*
X357165Y1249705D03*
Y1259705D03*
X362165Y1244705D03*
Y1254705D03*
X342165Y1429705D03*
X347165Y1424705D03*
Y1434705D03*
X342165Y1594705D03*
X357165Y1599705D03*
X362165Y1594705D03*
X357165Y1609705D03*
X362165Y1604705D03*
X347165Y1774705D03*
Y1784705D03*
X342165Y1944705D03*
X357165Y1949705D03*
Y1959705D03*
X362165Y1944705D03*
Y1954705D03*
G54D18*
G01X189762Y69353D02*
Y73105D01*
G01D02*
Y76857D01*
G01X186010Y73105D02*
X189762D01*
G01D02*
X193514D01*
G01X190289Y148298D02*
Y152050D01*
G01D02*
Y155802D01*
G01X186537Y152050D02*
X190289D01*
G01D02*
X194041D01*
G01X190357Y243816D02*
Y247568D01*
G01D02*
Y251320D01*
G01X186605Y247568D02*
X190357D01*
G01D02*
X194109D01*
G01X190817Y328034D02*
Y331786D01*
G01D02*
Y335538D01*
G01X187065Y331786D02*
X190817D01*
G01D02*
X194569D01*
G01X189761Y417980D02*
Y421732D01*
G01D02*
Y425484D01*
G01X186009Y421732D02*
X189761D01*
G01D02*
X193513D01*
G01X190553Y502765D02*
Y506517D01*
G01D02*
Y510269D01*
G01X186801Y506517D02*
X190553D01*
G01D02*
X194305D01*
G01X192888Y594378D02*
Y598130D01*
G01D02*
Y601882D01*
G01X189136Y598130D02*
X192888D01*
G01D02*
X196640D01*
G01X190816Y677893D02*
Y681645D01*
G01D02*
Y685397D01*
G01X187064Y681645D02*
X190816D01*
G01D02*
X194568D01*
G01X191846Y770774D02*
Y774526D01*
G01D02*
Y778278D01*
G01X188094Y774526D02*
X191846D01*
G01D02*
X195598D01*
G01X191606Y852492D02*
Y856244D01*
G01D02*
Y859996D01*
G01X187854Y856244D02*
X191606D01*
G01D02*
X195358D01*
G01X192559Y947202D02*
X196311D01*
G01X191250Y1119104D02*
Y1122856D01*
G01D02*
Y1126608D01*
G01X187498Y1122856D02*
X191250D01*
G01D02*
X195002D01*
G01X191342Y1202481D02*
Y1206233D01*
G01D02*
Y1209985D01*
G01X187590Y1206233D02*
X191342D01*
G01D02*
X195094D01*
G01X191846Y1295352D02*
Y1299104D01*
G01D02*
Y1302856D01*
G01X188094Y1299104D02*
X191846D01*
G01D02*
X195598D01*
G01X190552Y1377214D02*
Y1380966D01*
G01D02*
Y1384718D01*
G01X186800Y1380966D02*
X190552D01*
G01D02*
X194304D01*
G01X189463Y1470410D02*
Y1474162D01*
G01D02*
Y1477914D01*
G01X185711Y1474162D02*
X189463D01*
G01D02*
X193215D01*
G01X191079Y1553525D02*
Y1557277D01*
G01D02*
Y1561029D01*
G01X187327Y1557277D02*
X191079D01*
G01D02*
X194831D01*
G01X192143Y1644425D02*
Y1648177D01*
G01D02*
Y1651929D01*
G01X188391Y1648177D02*
X192143D01*
G01D02*
X195895D01*
G01X191607Y1727599D02*
Y1731351D01*
G01D02*
Y1735103D01*
G01X187855Y1731351D02*
X191607D01*
G01D02*
X195359D01*
G01X191530Y1819475D02*
Y1823227D01*
G01D02*
Y1826979D01*
G01X187778Y1823227D02*
X191530D01*
G01D02*
X195282D01*
G01X190289Y1896668D02*
Y1900420D01*
G01D02*
Y1904172D01*
G01X186537Y1900420D02*
X190289D01*
G01D02*
X194041D01*
G01X192125Y1994978D02*
Y1998730D01*
G01D02*
Y2002482D01*
G01X188373Y1998730D02*
X192125D01*
G01D02*
X195877D01*
G01X191530Y2039636D02*
Y2043388D01*
G01D02*
Y2047140D01*
G01X187778Y2043388D02*
X191530D01*
G01D02*
X195282D01*
G01X196311Y943450D02*
Y947202D01*
G01D02*
Y950954D01*
G01Y947202D02*
X200063D01*
G54D19*
G01X60815Y1019026D02*
Y1006877D01*
X73556Y994136D01*
X110818D01*
X116118Y988836D01*
X172220D01*
X173342Y989958D01*
X175742D01*
G01X63577Y1019115D02*
Y1008066D01*
X74903Y996740D01*
X111349D01*
X113967Y999358D01*
X173751D01*
X175449Y997660D01*
G01X96308Y696622D02*
X102960Y689970D01*
Y672823D01*
G01X76446Y1014871D02*
Y1011998D01*
X83040Y1005404D01*
X111094D01*
X115094Y1009404D01*
X159148D01*
X161520Y1007032D01*
X174000D01*
X175698Y1008730D01*
G01X79499Y1014871D02*
Y1013339D01*
X84613Y1008225D01*
X106505D01*
X117473Y1019193D01*
X151873D01*
X156009Y1015057D01*
X171834D01*
X173073Y1016296D01*
X175473D01*
G01X139920Y1122165D02*
X128348Y1110593D01*
Y1091203D01*
X124295Y1087150D01*
X106438D01*
X101079Y1081791D01*
X96684D01*
G01X257125Y115559D02*
X253079Y119605D01*
X237800D01*
X199955Y81760D01*
X156054D01*
X154945Y82869D01*
X137458D01*
X127836Y73247D01*
X114348D01*
X113345Y72244D01*
X107263D01*
G01X112836Y769122D02*
X127625D01*
X137564Y779061D01*
X149483D01*
X150933Y777611D01*
X177299D01*
X194109Y794421D01*
X215752D01*
X236367Y815036D01*
X252843D01*
X255687Y812192D01*
G01X105395Y972040D02*
X113199D01*
X115983Y969256D01*
X171901D01*
X175135Y972490D01*
G01X102611Y972220D02*
Y974646D01*
X107191Y979226D01*
X171567D01*
X172622Y980281D01*
X175022D01*
G01X301734Y1513883D02*
X297996Y1517621D01*
X248603D01*
X221966Y1490984D01*
X183263D01*
X166211Y1473932D01*
X152044D01*
X150679Y1475297D01*
X136271D01*
X125946Y1464972D01*
X114038D01*
X108574Y1463389D01*
G01X280240Y1858668D02*
X279040Y1859868D01*
X257788D01*
X233121Y1835201D01*
X189056D01*
X167071Y1813216D01*
X112317D01*
X111219Y1812118D01*
X108819D01*
G01X158901Y85017D02*
X198605D01*
X236450Y122862D01*
X251533D01*
X256947Y128276D01*
G01X255837Y823626D02*
X252883Y820672D01*
X237235D01*
X214707Y798144D01*
X192228D01*
X175066Y780982D01*
X158956D01*
G01X159216Y1477124D02*
X164276D01*
X181803Y1494651D01*
X221119D01*
X247280Y1520812D01*
X298678D01*
X302267Y1524401D01*
G01X279976Y1864565D02*
X278693Y1863282D01*
X256373D01*
X231706Y1838615D01*
X185711D01*
X172183Y1825087D01*
X159075D01*
M02*
